FILE_TYPE = MACRO_DRAWING;
SET COLOR_WIRE YELLOW;
SET COLOR_PROP ORANGE;
SET COLOR_DOT WHITE;
SET COLOR_ARC YELLOW;
SET COLOR_BODY GREEN;
SET COLOR_NOTE PURPLE;
SET PROP_DISPLAY VALUE;
SET PAGE_NUMBER P517;
FORCEADD GND_SG..1
(-12000 3400);
FORCEPROP 3 LASTPIN (-11950 3450) SIG_NAME SG\g
J 0
(-11940 3460);
DISPLAY 0.659574 (-11940 3460);
PAINT MONO (-11940 3460);
DISPLAY INVISIBLE (-11940 3460);
FORCEPROP 1 LAST HDL_POWER SG
J 1
(-11945 3305);
DISPLAY 0.808511 (-11945 3305);
PAINT GREEN (-11945 3305);
FORCEPROP 1 LAST PATH I1
J 0
(-11965 3400);
DISPLAY 0.808511 (-11965 3400);
PAINT GREEN (-11965 3400);
DISPLAY INVISIBLE (-11965 3400);
FORCEPROP 1 LAST BODY_TYPE PLUMBING
J 0
(-11985 3385);
DISPLAY 0.808511 (-11985 3385);
PAINT GREEN (-11985 3385);
DISPLAY INVISIBLE (-11985 3385);
FORCEPROP 2 LAST CDS_LIB cls
J 0
(-12000 3400);
DISPLAY INVISIBLE (-12000 3400);
FORCEPROP 1 LAST CDS_LMAN_SYM_OUTLINE 0,0,100,-50
J 0
(-12000 3400);
DISPLAY 0.468085 (-12000 3400);
PAINT GREEN (-12000 3400);
DISPLAY INVISIBLE (-12000 3400);
FORCEADD RESISTOR..2
(-11050 5300);
FORCEPROP 1 LAST $LOCATION R35
J 0
(-11000 5150);
DISPLAY 1.212766 (-11000 5150);
PAINT GREEN (-11000 5150);
FORCEPROP 0 LAST CDS_LOCATION R35
J 0
(-11000 5150);
DISPLAY 1.212766 (-11000 5150);
PAINT GREEN (-11000 5150);
DISPLAY INVISIBLE (-11000 5150);
FORCEPROP 0 LAST $SEC 1
J 0
(-11000 5450);
DISPLAY 0.680851 (-11000 5450);
PAINT MONO (-11000 5450);
DISPLAY INVISIBLE (-11000 5450);
FORCEPROP 0 LAST CDS_SEC 1
J 0
(-11000 5450);
DISPLAY 1.021277 (-11000 5450);
DISPLAY INVISIBLE (-11000 5450);
FORCEPROP 0 LASTPIN (-11050 5400) $PN 1
R 1
J 0
(-11060 5410);
DISPLAY 0.680851 (-11060 5410);
PAINT MONO (-11060 5410);
FORCEPROP 0 LASTPIN (-11050 5150) $PN 2
R 1
J 2
(-11060 5140);
DISPLAY 0.680851 (-11060 5140);
PAINT MONO (-11060 5140);
FORCEPROP 0 LAST PACKAGE 0402
J 0
(-10900 5250);
DISPLAY 1.021277 (-10900 5250);
FORCEPROP 1 LAST VALUE 100KOHM
J 0
(-11000 5350);
DISPLAY 1.212766 (-11000 5350);
PAINT GREEN (-11000 5350);
FORCEPROP 1 LAST PATH I10
J 0
(-11247 5405);
DISPLAY 1.212766 (-11247 5405);
PAINT GREEN (-11247 5405);
DISPLAY INVISIBLE (-11247 5405);
FORCEPROP 1 LAST TOLERANCE 1%
J 0
(-11247 5555);
DISPLAY 1.212766 (-11247 5555);
PAINT GREEN (-11247 5555);
DISPLAY INVISIBLE (-11247 5555);
FORCEPROP 1 LAST CLS_PN G155-11003-01
J 0
(-11186 5500);
DISPLAY 1.212766 (-11186 5500);
PAINT GREEN (-11186 5500);
DISPLAY INVISIBLE (-11186 5500);
FORCEPROP 1 LAST CDS_LMAN_SYM_OUTLINE -50,50,50,-100
J 0
(-11050 5300);
DISPLAY 0.468085 (-11050 5300);
PAINT GREEN (-11050 5300);
DISPLAY INVISIBLE (-11050 5300);
FORCEPROP 2 LAST CDS_LIB passive
J 0
(-11050 5300);
DISPLAY INVISIBLE (-11050 5300);
FORCEADD RESISTOR..2
(-13300 5750);
FORCEPROP 1 LAST $LOCATION R52
J 0
(-13550 5650);
DISPLAY 1.212766 (-13550 5650);
PAINT GREEN (-13550 5650);
FORCEPROP 0 LAST CDS_LOCATION R52
J 0
(-13750 5850);
DISPLAY 1.021277 (-13750 5850);
DISPLAY INVISIBLE (-13750 5850);
FORCEPROP 0 LAST $SEC 1
J 0
(-13750 5850);
DISPLAY 0.680851 (-13750 5850);
PAINT MONO (-13750 5850);
DISPLAY INVISIBLE (-13750 5850);
FORCEPROP 0 LAST CDS_SEC 1
J 0
(-13750 5850);
DISPLAY 1.021277 (-13750 5850);
DISPLAY INVISIBLE (-13750 5850);
FORCEPROP 0 LASTPIN (-13300 5850) $PN 1
R 1
J 0
(-13310 5860);
DISPLAY 0.680851 (-13310 5860);
PAINT MONO (-13310 5860);
FORCEPROP 0 LASTPIN (-13300 5600) $PN 2
R 1
J 2
(-13310 5590);
DISPLAY 0.680851 (-13310 5590);
PAINT MONO (-13310 5590);
FORCEPROP 1 LAST VALUE 5.1KOHM
J 0
(-13750 5750);
DISPLAY 1.212766 (-13750 5750);
PAINT GREEN (-13750 5750);
FORCEPROP 0 LAST PACKAGE 0402
J 0
(-13600 5850);
DISPLAY 1.021277 (-13600 5850);
FORCEPROP 1 LAST PATH I11
J 0
(-13497 5855);
DISPLAY 1.212766 (-13497 5855);
PAINT GREEN (-13497 5855);
DISPLAY INVISIBLE (-13497 5855);
FORCEPROP 1 LAST TOLERANCE 1%
J 0
(-13497 6005);
DISPLAY 1.212766 (-13497 6005);
PAINT GREEN (-13497 6005);
DISPLAY INVISIBLE (-13497 6005);
FORCEPROP 1 LAST CLS_PN G155-05101-01
J 0
(-13436 5950);
DISPLAY 1.212766 (-13436 5950);
PAINT GREEN (-13436 5950);
DISPLAY INVISIBLE (-13436 5950);
FORCEPROP 1 LAST CDS_LMAN_SYM_OUTLINE -50,50,50,-100
J 0
(-13300 5750);
DISPLAY 0.468085 (-13300 5750);
PAINT GREEN (-13300 5750);
DISPLAY INVISIBLE (-13300 5750);
FORCEPROP 2 LAST CDS_LIB passive
J 0
(-13300 5750);
DISPLAY INVISIBLE (-13300 5750);
FORCEADD CAPACITOR..2
(-12350 5800);
FORCEPROP 1 LAST $LOCATION C46
J 0
(-12250 5850);
DISPLAY 1.212766 (-12250 5850);
PAINT GREEN (-12250 5850);
FORCEPROP 0 LAST CDS_LOCATION C46
J 0
(-12250 6050);
DISPLAY INVISIBLE (-12250 6050);
FORCEPROP 0 LAST $SEC 1
J 0
(-12300 5950);
PAINT MONO (-12300 5950);
DISPLAY INVISIBLE (-12300 5950);
FORCEPROP 0 LAST CDS_SEC 1
J 0
(-12300 5950);
PAINT MONO (-12300 5950);
DISPLAY INVISIBLE (-12300 5950);
FORCEPROP 0 LASTPIN (-12350 5900) $PN 1
R 1
J 0
(-12360 5910);
DISPLAY 0.808511 (-12360 5910);
PAINT MONO (-12360 5910);
FORCEPROP 0 LASTPIN (-12350 5650) $PN 2
R 1
J 2
(-12360 5640);
DISPLAY 0.808511 (-12360 5640);
PAINT MONO (-12360 5640);
FORCEPROP 1 LAST VALUE 0.1UF
J 0
(-12250 5650);
DISPLAY 1.212766 (-12250 5650);
PAINT GREEN (-12250 5650);
FORCEPROP 0 LAST PACKAGE 0402
J 0
(-12250 6000);
DISPLAY 1.021277 (-12250 6000);
FORCEPROP 0 LAST VOLTAGE 10V
J 0
(-12250 6100);
DISPLAY 1.021277 (-12250 6100);
FORCEPROP 1 LAST PATH I12
J 0
(-12450 5850);
DISPLAY 1.212766 (-12450 5850);
PAINT GREEN (-12450 5850);
DISPLAY INVISIBLE (-12450 5850);
FORCEPROP 2 LAST CDS_LIB passive
J 0
(-12350 5800);
DISPLAY INVISIBLE (-12350 5800);
FORCEPROP 1 LAST CDS_LMAN_SYM_OUTLINE -50,0,50,-50
J 0
(-12350 5800);
DISPLAY 0.468085 (-12350 5800);
PAINT GREEN (-12350 5800);
DISPLAY INVISIBLE (-12350 5800);
FORCEPROP 1 LAST TOLERANCE 10%
J 0
(-12500 5900);
DISPLAY 1.212766 (-12500 5900);
PAINT GREEN (-12500 5900);
DISPLAY INVISIBLE (-12500 5900);
FORCEPROP 1 LAST CLS_PN G105-0B104-CK
J 0
(-12450 5850);
DISPLAY 1.212766 (-12450 5850);
PAINT GREEN (-12450 5850);
DISPLAY INVISIBLE (-12450 5850);
FORCEADD RESISTOR..2
(-12550 6850);
FORCEPROP 1 LAST $LOCATION R53
J 0
(-12500 6700);
DISPLAY 1.212766 (-12500 6700);
PAINT GREEN (-12500 6700);
FORCEPROP 0 LAST CDS_LOCATION R53
J 0
(-12950 6950);
DISPLAY 1.021277 (-12950 6950);
DISPLAY INVISIBLE (-12950 6950);
FORCEPROP 0 LAST $SEC 1
J 0
(-12950 6950);
DISPLAY 0.680851 (-12950 6950);
PAINT MONO (-12950 6950);
DISPLAY INVISIBLE (-12950 6950);
FORCEPROP 0 LAST CDS_SEC 1
J 0
(-12950 6950);
DISPLAY 1.021277 (-12950 6950);
DISPLAY INVISIBLE (-12950 6950);
FORCEPROP 0 LASTPIN (-12550 6950) $PN 1
R 1
J 0
(-12560 6960);
DISPLAY 0.680851 (-12560 6960);
PAINT MONO (-12560 6960);
FORCEPROP 0 LASTPIN (-12550 6700) $PN 2
R 1
J 2
(-12560 6690);
DISPLAY 0.680851 (-12560 6690);
PAINT MONO (-12560 6690);
FORCEPROP 0 LAST PACKAGE 0402
J 0
(-12500 7000);
DISPLAY 1.021277 (-12500 7000);
FORCEPROP 1 LAST VALUE 30KOHM
J 0
(-12500 6850);
DISPLAY 1.212766 (-12500 6850);
PAINT GREEN (-12500 6850);
FORCEPROP 1 LAST CLS_PN G152-10344-01
J 0
(-12686 7050);
DISPLAY 1.212766 (-12686 7050);
PAINT GREEN (-12686 7050);
DISPLAY INVISIBLE (-12686 7050);
FORCEPROP 1 LAST TOLERANCE 0.1%
J 0
(-12747 7105);
DISPLAY 1.212766 (-12747 7105);
PAINT GREEN (-12747 7105);
DISPLAY INVISIBLE (-12747 7105);
FORCEPROP 2 LAST CDS_LIB passive
J 0
(-12550 6850);
DISPLAY INVISIBLE (-12550 6850);
FORCEPROP 1 LAST CDS_LMAN_SYM_OUTLINE -50,50,50,-100
J 0
(-12550 6850);
DISPLAY 0.468085 (-12550 6850);
PAINT GREEN (-12550 6850);
DISPLAY INVISIBLE (-12550 6850);
FORCEPROP 1 LAST PATH I13
J 0
(-12747 6955);
DISPLAY 1.212766 (-12747 6955);
PAINT GREEN (-12747 6955);
DISPLAY INVISIBLE (-12747 6955);
FORCEADD CAPACITOR..2
(-12000 7150);
FORCEPROP 1 LAST $LOCATION C48
J 0
(-11950 7200);
DISPLAY 1.212766 (-11950 7200);
PAINT GREEN (-11950 7200);
FORCEPROP 0 LAST CDS_LOCATION C48
J 0
(-11950 7400);
DISPLAY INVISIBLE (-11950 7400);
FORCEPROP 0 LAST $SEC 1
J 0
(-11950 7300);
DISPLAY INVISIBLE (-11950 7300);
FORCEPROP 0 LAST CDS_SEC 1
J 0
(-11950 7300);
DISPLAY INVISIBLE (-11950 7300);
FORCEPROP 0 LASTPIN (-12000 7250) $PN 1
R 1
J 0
(-12010 7260);
DISPLAY 0.808511 (-12010 7260);
FORCEPROP 0 LASTPIN (-12000 7000) $PN 2
R 1
J 2
(-12010 6990);
DISPLAY 0.808511 (-12010 6990);
FORCEPROP 1 LAST VALUE 10UF
J 0
(-11950 7100);
DISPLAY 1.212766 (-11950 7100);
PAINT GREEN (-11950 7100);
FORCEPROP 0 LAST VOLTAGE 25V
J 0
(-11950 7450);
DISPLAY 1.021277 (-11950 7450);
FORCEPROP 0 LAST PACKAGE 0805
J 0
(-11950 7350);
DISPLAY 1.021277 (-11950 7350);
FORCEPROP 1 LAST PATH I14
J 0
(-12100 7200);
DISPLAY 1.212766 (-12100 7200);
PAINT GREEN (-12100 7200);
DISPLAY INVISIBLE (-12100 7200);
FORCEPROP 1 LAST TOLERANCE 20%
J 0
(-12150 7250);
DISPLAY 1.212766 (-12150 7250);
PAINT GREEN (-12150 7250);
DISPLAY INVISIBLE (-12150 7250);
FORCEPROP 2 LAST CDS_LIB passive
J 0
(-12000 7150);
DISPLAY INVISIBLE (-12000 7150);
FORCEPROP 1 LAST CDS_LMAN_SYM_OUTLINE -50,0,50,-50
J 0
(-12000 7150);
DISPLAY 0.468085 (-12000 7150);
PAINT GREEN (-12000 7150);
DISPLAY INVISIBLE (-12000 7150);
FORCEPROP 1 LAST CLS_PN G107-0F106-EM
J 0
(-12100 7200);
DISPLAY 1.212766 (-12100 7200);
PAINT GREEN (-12100 7200);
DISPLAY INVISIBLE (-12100 7200);
FORCEADD CAPACITOR..2
(-11550 7150);
FORCEPROP 1 LAST $LOCATION C50
J 0
(-11500 7200);
DISPLAY 1.212766 (-11500 7200);
PAINT GREEN (-11500 7200);
FORCEPROP 0 LAST CDS_LOCATION C50
J 0
(-11500 7400);
DISPLAY INVISIBLE (-11500 7400);
FORCEPROP 0 LAST $SEC 1
J 0
(-11500 7300);
DISPLAY INVISIBLE (-11500 7300);
FORCEPROP 0 LAST CDS_SEC 1
J 0
(-11500 7300);
DISPLAY INVISIBLE (-11500 7300);
FORCEPROP 0 LASTPIN (-11550 7250) $PN 1
R 1
J 0
(-11560 7260);
DISPLAY 0.808511 (-11560 7260);
FORCEPROP 0 LASTPIN (-11550 7000) $PN 2
R 1
J 2
(-11560 6990);
DISPLAY 0.808511 (-11560 6990);
FORCEPROP 1 LAST VALUE 10UF
J 0
(-11500 7100);
DISPLAY 1.212766 (-11500 7100);
PAINT GREEN (-11500 7100);
FORCEPROP 0 LAST PACKAGE 0805
J 0
(-11500 7350);
DISPLAY 1.021277 (-11500 7350);
FORCEPROP 0 LAST VOLTAGE 25V
J 0
(-11500 7450);
DISPLAY 1.021277 (-11500 7450);
FORCEPROP 1 LAST PATH I15
J 0
(-11650 7200);
DISPLAY 1.212766 (-11650 7200);
PAINT GREEN (-11650 7200);
DISPLAY INVISIBLE (-11650 7200);
FORCEPROP 2 LAST CDS_LIB passive
J 0
(-11550 7150);
DISPLAY INVISIBLE (-11550 7150);
FORCEPROP 1 LAST CDS_LMAN_SYM_OUTLINE -50,0,50,-50
J 0
(-11550 7150);
DISPLAY 0.468085 (-11550 7150);
PAINT GREEN (-11550 7150);
DISPLAY INVISIBLE (-11550 7150);
FORCEPROP 1 LAST CLS_PN G107-0F106-EM
J 0
(-11650 7200);
DISPLAY 1.212766 (-11650 7200);
PAINT GREEN (-11650 7200);
DISPLAY INVISIBLE (-11650 7200);
FORCEPROP 1 LAST TOLERANCE 20%
J 0
(-11700 7250);
DISPLAY 1.212766 (-11700 7250);
PAINT GREEN (-11700 7250);
DISPLAY INVISIBLE (-11700 7250);
FORCEADD CAPACITOR..2
(-11100 7150);
FORCEPROP 1 LAST $LOCATION C52
J 0
(-11000 7200);
DISPLAY 1.212766 (-11000 7200);
PAINT GREEN (-11000 7200);
FORCEPROP 0 LAST CDS_LOCATION C52
J 0
(-11000 7300);
DISPLAY 1.021277 (-11000 7300);
DISPLAY INVISIBLE (-11000 7300);
FORCEPROP 0 LAST $SEC 1
J 0
(-11000 7300);
DISPLAY 0.680851 (-11000 7300);
PAINT MONO (-11000 7300);
DISPLAY INVISIBLE (-11000 7300);
FORCEPROP 0 LAST CDS_SEC 1
J 0
(-11000 7300);
DISPLAY 1.021277 (-11000 7300);
DISPLAY INVISIBLE (-11000 7300);
FORCEPROP 0 LASTPIN (-11100 7250) $PN 1
R 1
J 0
(-11110 7260);
DISPLAY 0.680851 (-11110 7260);
PAINT MONO (-11110 7260);
FORCEPROP 0 LASTPIN (-11100 7000) $PN 2
R 1
J 2
(-11110 6990);
DISPLAY 0.680851 (-11110 6990);
PAINT MONO (-11110 6990);
FORCEPROP 1 LAST VALUE 0.1UF
J 0
(-11000 7000);
DISPLAY 1.212766 (-11000 7000);
PAINT GREEN (-11000 7000);
FORCEPROP 0 LAST PACKAGE 0402
J 0
(-11000 7350);
DISPLAY 1.021277 (-11000 7350);
FORCEPROP 0 LAST VOLTAGE 25V
J 0
(-11000 7450);
DISPLAY 1.021277 (-11000 7450);
FORCEPROP 1 LAST PATH I16
J 0
(-11200 7200);
DISPLAY 1.212766 (-11200 7200);
PAINT GREEN (-11200 7200);
DISPLAY INVISIBLE (-11200 7200);
FORCEPROP 2 LAST CDS_LIB passive
J 0
(-11100 7150);
DISPLAY INVISIBLE (-11100 7150);
FORCEPROP 1 LAST CDS_LMAN_SYM_OUTLINE -50,0,50,-50
J 0
(-11100 7150);
DISPLAY 0.468085 (-11100 7150);
PAINT GREEN (-11100 7150);
DISPLAY INVISIBLE (-11100 7150);
FORCEPROP 1 LAST CLS_PN G105-0B104-EK
J 0
(-11200 7200);
DISPLAY 1.212766 (-11200 7200);
PAINT GREEN (-11200 7200);
DISPLAY INVISIBLE (-11200 7200);
FORCEPROP 1 LAST TOLERANCE 10%
J 0
(-11250 7250);
DISPLAY 1.212766 (-11250 7250);
PAINT GREEN (-11250 7250);
DISPLAY INVISIBLE (-11250 7250);
FORCEADD CAPACITOR..2
(-10400 4900);
FORCEPROP 1 LAST $LOCATION C54
J 0
(-10350 4950);
DISPLAY 1.212766 (-10350 4950);
PAINT GREEN (-10350 4950);
FORCEPROP 0 LAST CDS_LOCATION C54
J 0
(-10350 4750);
DISPLAY 1.212766 (-10350 4750);
PAINT GREEN (-10350 4750);
DISPLAY INVISIBLE (-10350 4750);
FORCEPROP 0 LAST $SEC 1
J 0
(-10350 5050);
DISPLAY 0.680851 (-10350 5050);
PAINT MONO (-10350 5050);
DISPLAY INVISIBLE (-10350 5050);
FORCEPROP 0 LAST CDS_SEC 1
J 0
(-10350 5050);
DISPLAY 1.021277 (-10350 5050);
DISPLAY INVISIBLE (-10350 5050);
FORCEPROP 0 LASTPIN (-10400 5000) $PN 1
R 1
J 0
(-10410 5010);
DISPLAY 0.680851 (-10410 5010);
PAINT MONO (-10410 5010);
FORCEPROP 0 LASTPIN (-10400 4750) $PN 2
R 1
J 2
(-10410 4740);
DISPLAY 0.680851 (-10410 4740);
PAINT MONO (-10410 4740);
FORCEPROP 0 LAST VOLTAGE 50V
J 0
(-10150 4950);
DISPLAY 1.021277 (-10150 4950);
FORCEPROP 1 LAST VALUE 2200PF
J 0
(-10350 4750);
DISPLAY 1.212766 (-10350 4750);
PAINT GREEN (-10350 4750);
FORCEPROP 0 LAST PACKAGE 0402
J 0
(-10300 4850);
DISPLAY 1.021277 (-10300 4850);
FORCEPROP 1 LAST CLS_PN G105-0B222-FK
J 0
(-10500 4950);
DISPLAY 1.212766 (-10500 4950);
PAINT GREEN (-10500 4950);
DISPLAY INVISIBLE (-10500 4950);
FORCEPROP 2 LASTPIN (-10400 5000) SIG_NAME UN$517$CAPACITOR$I17$1
J 0
(-10390 5010);
DISPLAY 0.659574 (-10390 5010);
PAINT MONO (-10390 5010);
DISPLAY INVISIBLE (-10390 5010);
FORCEPROP 2 LAST CDS_LIB passive
J 0
(-10400 4900);
DISPLAY INVISIBLE (-10400 4900);
FORCEPROP 1 LAST CDS_LMAN_SYM_OUTLINE -50,0,50,-50
J 0
(-10400 4900);
DISPLAY 0.468085 (-10400 4900);
PAINT GREEN (-10400 4900);
DISPLAY INVISIBLE (-10400 4900);
FORCEPROP 1 LAST TOLERANCE 10%
J 0
(-10550 5000);
DISPLAY 1.212766 (-10550 5000);
PAINT GREEN (-10550 5000);
DISPLAY INVISIBLE (-10550 5000);
FORCEPROP 1 LAST PATH I17
J 0
(-10500 4950);
DISPLAY 1.212766 (-10500 4950);
PAINT GREEN (-10500 4950);
DISPLAY INVISIBLE (-10500 4950);
FORCEADD RESISTOR..2
(-10400 5200);
FORCEPROP 1 LAST $LOCATION R36
J 0
(-10350 5200);
DISPLAY 1.212766 (-10350 5200);
PAINT GREEN (-10350 5200);
FORCEPROP 0 LAST CDS_LOCATION R36
J 0
(-10350 5050);
DISPLAY 1.212766 (-10350 5050);
PAINT GREEN (-10350 5050);
DISPLAY INVISIBLE (-10350 5050);
FORCEPROP 0 LAST $SEC 1
J 0
(-10350 5350);
DISPLAY 0.680851 (-10350 5350);
PAINT MONO (-10350 5350);
DISPLAY INVISIBLE (-10350 5350);
FORCEPROP 0 LAST CDS_SEC 1
J 0
(-10350 5350);
DISPLAY 1.021277 (-10350 5350);
DISPLAY INVISIBLE (-10350 5350);
FORCEPROP 0 LASTPIN (-10400 5300) $PN 1
R 1
J 0
(-10410 5310);
DISPLAY 0.680851 (-10410 5310);
PAINT MONO (-10410 5310);
FORCEPROP 0 LASTPIN (-10400 5050) $PN 2
R 1
J 2
(-10410 5040);
DISPLAY 0.680851 (-10410 5040);
PAINT MONO (-10410 5040);
FORCEPROP 1 LAST VALUE 10KOHM
J 0
(-10350 5100);
DISPLAY 1.212766 (-10350 5100);
PAINT GREEN (-10350 5100);
FORCEPROP 0 LAST PACKAGE 0402
J 0
(-10200 5200);
DISPLAY 1.021277 (-10200 5200);
FORCEPROP 1 LAST CLS_PN G155-11002-01
J 0
(-10536 5400);
DISPLAY 1.212766 (-10536 5400);
PAINT GREEN (-10536 5400);
DISPLAY INVISIBLE (-10536 5400);
FORCEPROP 2 LAST CDS_LIB passive
J 0
(-10400 5200);
DISPLAY INVISIBLE (-10400 5200);
FORCEPROP 1 LAST CDS_LMAN_SYM_OUTLINE -50,50,50,-100
J 0
(-10400 5200);
DISPLAY 0.468085 (-10400 5200);
PAINT GREEN (-10400 5200);
DISPLAY INVISIBLE (-10400 5200);
FORCEPROP 1 LAST TOLERANCE 1%
J 0
(-10597 5455);
DISPLAY 1.212766 (-10597 5455);
PAINT GREEN (-10597 5455);
DISPLAY INVISIBLE (-10597 5455);
FORCEPROP 1 LAST PATH I18
J 0
(-10597 5305);
DISPLAY 1.212766 (-10597 5305);
PAINT GREEN (-10597 5305);
DISPLAY INVISIBLE (-10597 5305);
FORCEADD CAPACITOR..2
(-9800 5050);
FORCEPROP 1 LAST $LOCATION C55
J 0
(-9750 4900);
DISPLAY 1.212766 (-9750 4900);
PAINT GREEN (-9750 4900);
FORCEPROP 0 LAST CDS_LOCATION C55
J 0
(-9750 4900);
DISPLAY 1.212766 (-9750 4900);
PAINT GREEN (-9750 4900);
DISPLAY INVISIBLE (-9750 4900);
FORCEPROP 0 LAST $SEC 1
J 0
(-9750 5200);
DISPLAY 0.680851 (-9750 5200);
PAINT MONO (-9750 5200);
DISPLAY INVISIBLE (-9750 5200);
FORCEPROP 0 LAST CDS_SEC 1
J 0
(-9750 5200);
DISPLAY 1.021277 (-9750 5200);
DISPLAY INVISIBLE (-9750 5200);
FORCEPROP 0 LASTPIN (-9800 5150) $PN 1
R 1
J 0
(-9810 5160);
DISPLAY 0.680851 (-9810 5160);
PAINT MONO (-9810 5160);
FORCEPROP 0 LASTPIN (-9800 4900) $PN 2
R 1
J 2
(-9810 4890);
DISPLAY 0.680851 (-9810 4890);
PAINT MONO (-9810 4890);
FORCEPROP 0 LAST PACKAGE 0201
J 0
(-9750 4800);
DISPLAY 1.021277 (-9750 4800);
FORCEPROP 0 LAST VOLTAGE 25V
J 0
(-9750 5250);
DISPLAY 1.021277 (-9750 5250);
FORCEPROP 1 LAST VALUE 18PF
J 0
(-9750 5100);
DISPLAY 1.212766 (-9750 5100);
PAINT GREEN (-9750 5100);
FORCEPROP 1 LAST PATH I19
J 0
(-9900 5100);
DISPLAY 1.212766 (-9900 5100);
PAINT GREEN (-9900 5100);
DISPLAY INVISIBLE (-9900 5100);
FORCEPROP 1 LAST TOLERANCE 5%
J 0
(-9950 5150);
DISPLAY 1.212766 (-9950 5150);
PAINT GREEN (-9950 5150);
DISPLAY INVISIBLE (-9950 5150);
FORCEPROP 2 LAST CDS_LIB passive
J 0
(-9800 5050);
DISPLAY INVISIBLE (-9800 5050);
FORCEPROP 1 LAST CDS_LMAN_SYM_OUTLINE -50,0,50,-50
J 0
(-9800 5050);
DISPLAY 0.468085 (-9800 5050);
PAINT GREEN (-9800 5050);
DISPLAY INVISIBLE (-9800 5050);
FORCEPROP 1 LAST CLS_PN G104-0A180-FJ
J 0
(-9900 5100);
DISPLAY 1.212766 (-9900 5100);
PAINT GREEN (-9900 5100);
DISPLAY INVISIBLE (-9900 5100);
FORCEADD CAPACITOR..1
R 1
(-11950 3700);
FORCEPROP 1 LAST $LOCATION C77
R 1
J 2
(-12050 3800);
DISPLAY 1.212766 (-12050 3800);
PAINT GREEN (-12050 3800);
FORCEPROP 0 LAST CDS_LOCATION C77
R 1
J 0
(-11850 3900);
DISPLAY 1.021277 (-11850 3900);
DISPLAY INVISIBLE (-11850 3900);
FORCEPROP 0 LAST $SEC 1
R 1
J 0
(-11850 3900);
DISPLAY 0.680851 (-11850 3900);
PAINT MONO (-11850 3900);
DISPLAY INVISIBLE (-11850 3900);
FORCEPROP 0 LAST CDS_SEC 1
R 1
J 0
(-11850 3900);
DISPLAY 1.021277 (-11850 3900);
DISPLAY INVISIBLE (-11850 3900);
FORCEPROP 0 LASTPIN (-11950 3600) $PN 1
R 1
J 2
(-11960 3590);
DISPLAY 0.680851 (-11960 3590);
PAINT MONO (-11960 3590);
FORCEPROP 0 LASTPIN (-11950 3850) $PN 2
R 1
J 0
(-11960 3860);
DISPLAY 0.680851 (-11960 3860);
PAINT MONO (-11960 3860);
FORCEPROP 0 LAST VOLTAGE 25V
R 1
J 0
(-11850 3950);
DISPLAY 1.021277 (-11850 3950);
FORCEPROP 1 LAST VALUE 0.01UF
J 0
(-11850 3800);
DISPLAY 1.212766 (-11850 3800);
PAINT GREEN (-11850 3800);
FORCEPROP 0 LAST PACKAGE 0402
R 1
J 0
(-11850 3950);
DISPLAY 1.021277 (-11850 3950);
FORCEPROP 1 LAST PATH I2
R 1
J 2
(-12050 3650);
DISPLAY 1.212766 (-12050 3650);
PAINT GREEN (-12050 3650);
DISPLAY INVISIBLE (-12050 3650);
FORCEPROP 1 LAST CLS_PN G104-0B103-EK
R 1
J 2
(-12050 3650);
DISPLAY 1.212766 (-12050 3650);
PAINT GREEN (-12050 3650);
DISPLAY INVISIBLE (-12050 3650);
FORCEPROP 1 LAST CDS_LMAN_SYM_OUTLINE 0,50,50,-50
R 1
J 0
(-11950 3700);
DISPLAY 0.468085 (-11950 3700);
PAINT GREEN (-11950 3700);
DISPLAY INVISIBLE (-11950 3700);
FORCEPROP 2 LAST CDS_LIB passive
J 0
(-11950 3700);
DISPLAY INVISIBLE (-11950 3700);
FORCEPROP 1 LAST TOLERANCE 10%
R 1
J 2
(-12050 3600);
DISPLAY 1.212766 (-12050 3600);
PAINT GREEN (-12050 3600);
DISPLAY INVISIBLE (-12050 3600);
FORCEADD GND_SG..1
(-10600 6600);
FORCEPROP 3 LASTPIN (-10550 6650) SIG_NAME SG\g
J 0
(-10540 6660);
DISPLAY 0.659574 (-10540 6660);
PAINT MONO (-10540 6660);
DISPLAY INVISIBLE (-10540 6660);
FORCEPROP 1 LAST HDL_POWER SG
J 1
(-10545 6505);
DISPLAY 0.808511 (-10545 6505);
PAINT GREEN (-10545 6505);
FORCEPROP 1 LAST PATH I20
J 0
(-10565 6600);
DISPLAY 0.808511 (-10565 6600);
PAINT GREEN (-10565 6600);
DISPLAY INVISIBLE (-10565 6600);
FORCEPROP 1 LAST BODY_TYPE PLUMBING
J 0
(-10585 6585);
DISPLAY 0.808511 (-10585 6585);
PAINT GREEN (-10585 6585);
DISPLAY INVISIBLE (-10585 6585);
FORCEPROP 2 LAST CDS_LIB cls
J 0
(-10600 6600);
DISPLAY INVISIBLE (-10600 6600);
FORCEPROP 1 LAST CDS_LMAN_SYM_OUTLINE 0,0,100,-50
J 0
(-10600 6600);
DISPLAY 0.468085 (-10600 6600);
PAINT GREEN (-10600 6600);
DISPLAY INVISIBLE (-10600 6600);
FORCEADD CAPACITOR..2
(-10550 7150);
FORCEPROP 1 LAST $LOCATION C53
J 0
(-10450 7200);
DISPLAY 1.212766 (-10450 7200);
PAINT GREEN (-10450 7200);
FORCEPROP 0 LAST CDS_LOCATION C53
J 0
(-10450 7200);
DISPLAY 1.021277 (-10450 7200);
DISPLAY INVISIBLE (-10450 7200);
FORCEPROP 0 LAST $SEC 1
J 0
(-10450 7200);
DISPLAY 0.680851 (-10450 7200);
PAINT MONO (-10450 7200);
DISPLAY INVISIBLE (-10450 7200);
FORCEPROP 0 LAST CDS_SEC 1
J 0
(-10450 7200);
DISPLAY 1.021277 (-10450 7200);
DISPLAY INVISIBLE (-10450 7200);
FORCEPROP 0 LASTPIN (-10550 7250) $PN 1
R 1
J 0
(-10560 7260);
DISPLAY 0.680851 (-10560 7260);
PAINT MONO (-10560 7260);
FORCEPROP 0 LASTPIN (-10550 7000) $PN 2
R 1
J 2
(-10560 6990);
DISPLAY 0.680851 (-10560 6990);
PAINT MONO (-10560 6990);
FORCEPROP 1 LAST VALUE 0.1UF
J 0
(-10450 7000);
DISPLAY 1.212766 (-10450 7000);
PAINT GREEN (-10450 7000);
FORCEPROP 0 LAST PACKAGE 0402
J 0
(-10450 7350);
DISPLAY 1.021277 (-10450 7350);
FORCEPROP 0 LAST VOLTAGE 25V
J 0
(-10450 7450);
DISPLAY 1.021277 (-10450 7450);
FORCEPROP 1 LAST PATH I21
J 0
(-10650 7200);
DISPLAY 1.212766 (-10650 7200);
PAINT GREEN (-10650 7200);
DISPLAY INVISIBLE (-10650 7200);
FORCEPROP 1 LAST CLS_PN G105-0B104-EK
J 0
(-10650 7200);
DISPLAY 1.212766 (-10650 7200);
PAINT GREEN (-10650 7200);
DISPLAY INVISIBLE (-10650 7200);
FORCEPROP 2 LAST CDS_LIB passive
J 0
(-10550 7150);
DISPLAY INVISIBLE (-10550 7150);
FORCEPROP 1 LAST CDS_LMAN_SYM_OUTLINE -50,0,50,-50
J 0
(-10550 7150);
DISPLAY 0.468085 (-10550 7150);
PAINT GREEN (-10550 7150);
DISPLAY INVISIBLE (-10550 7150);
FORCEPROP 1 LAST TOLERANCE 10%
J 0
(-10700 7250);
DISPLAY 1.212766 (-10700 7250);
PAINT GREEN (-10700 7250);
DISPLAY INVISIBLE (-10700 7250);
FORCEADD VCC..1
(-13800 7900);
FORCEPROP 3 LASTPIN (-13750 7850) SIG_NAME XP12R0V\g
J 0
(-13740 7860);
DISPLAY 0.659574 (-13740 7860);
PAINT MONO (-13740 7860);
DISPLAY INVISIBLE (-13740 7860);
FORCEPROP 1 LAST HDL_POWER XP12R0V
J 1
(-13745 7955);
DISPLAY 1.021277 (-13745 7955);
PAINT GREEN (-13745 7955);
FORCEPROP 0 LAST VOLTAGE 12V
J 0
(-14000 8000);
DISPLAY 1.021277 (-14000 8000);
DISPLAY BOTH (-14000 8000);
FORCEPROP 1 LAST PATH I22
J 0
(-13765 7990);
DISPLAY 0.808511 (-13765 7990);
PAINT GREEN (-13765 7990);
DISPLAY INVISIBLE (-13765 7990);
FORCEPROP 1 LAST BODY_TYPE PLUMBING
J 0
(-13845 7857);
DISPLAY 0.340426 (-13845 7857);
PAINT GREEN (-13845 7857);
DISPLAY INVISIBLE (-13845 7857);
FORCEPROP 1 LAST CDS_LMAN_SYM_OUTLINE -250,250,250,-250
J 0
(-13800 7900);
DISPLAY 0.468085 (-13800 7900);
PAINT GREEN (-13800 7900);
DISPLAY INVISIBLE (-13800 7900);
FORCEPROP 2 LAST CDS_LIB cls
J 0
(-13800 7900);
DISPLAY INVISIBLE (-13800 7900);
FORCEADD GND_SG..1
(-7800 3950);
FORCEPROP 3 LASTPIN (-7750 4000) SIG_NAME SG\g
J 0
(-7740 4010);
DISPLAY 0.659574 (-7740 4010);
PAINT MONO (-7740 4010);
DISPLAY INVISIBLE (-7740 4010);
FORCEPROP 1 LAST HDL_POWER SG
J 1
(-7745 3855);
DISPLAY 0.808511 (-7745 3855);
PAINT GREEN (-7745 3855);
FORCEPROP 1 LAST PATH I23
J 0
(-7765 3950);
DISPLAY 0.808511 (-7765 3950);
PAINT GREEN (-7765 3950);
DISPLAY INVISIBLE (-7765 3950);
FORCEPROP 1 LAST BODY_TYPE PLUMBING
J 0
(-7785 3935);
DISPLAY 0.808511 (-7785 3935);
PAINT GREEN (-7785 3935);
DISPLAY INVISIBLE (-7785 3935);
FORCEPROP 1 LAST CDS_LMAN_SYM_OUTLINE 0,0,100,-50
J 0
(-7800 3950);
DISPLAY 0.468085 (-7800 3950);
PAINT GREEN (-7800 3950);
DISPLAY INVISIBLE (-7800 3950);
FORCEPROP 2 LAST CDS_LIB cls
J 0
(-7800 3950);
DISPLAY INVISIBLE (-7800 3950);
FORCEADD SOLDER_PREFORM..1
(-7150 4350);
FORCEPROP 1 LAST $LOCATION SP2
J 0
(-7100 4450);
DISPLAY 1.212766 (-7100 4450);
PAINT GREEN (-7100 4450);
FORCEPROP 0 LAST CDS_LOCATION SP2
J 0
(-7100 4750);
DISPLAY 1.021277 (-7100 4750);
DISPLAY INVISIBLE (-7100 4750);
FORCEPROP 0 LAST $SEC 1
J 0
(-7100 4650);
DISPLAY 0.680851 (-7100 4650);
PAINT MONO (-7100 4650);
DISPLAY INVISIBLE (-7100 4650);
FORCEPROP 0 LAST CDS_SEC 1
J 0
(-7100 4750);
DISPLAY 1.021277 (-7100 4750);
DISPLAY INVISIBLE (-7100 4750);
FORCEPROP 0 LASTPIN (-7250 4250) $PN 1
J 2
(-7260 4260);
DISPLAY 0.680851 (-7260 4260);
PAINT MONO (-7260 4260);
FORCEPROP 0 LASTPIN (-6800 4250) $PN 2
J 0
(-6790 4260);
DISPLAY 0.680851 (-6790 4260);
PAINT MONO (-6790 4260);
FORCEPROP 1 LAST CLS_PN G380-10015-01
J 0
(-7100 4550);
DISPLAY 1.212766 (-7100 4550);
PAINT GREEN (-7100 4550);
FORCEPROP 1 LAST PATH I24
J 0
(-7100 4400);
DISPLAY 1.212766 (-7100 4400);
PAINT GREEN (-7100 4400);
DISPLAY INVISIBLE (-7100 4400);
FORCEPROP 1 LAST CDS_LMAN_SYM_OUTLINE 0,0,250,-200
J 0
(-7150 4350);
DISPLAY 0.468085 (-7150 4350);
PAINT GREEN (-7150 4350);
DISPLAY INVISIBLE (-7150 4350);
FORCEPROP 2 LAST CDS_LIB mech
J 0
(-7150 4350);
DISPLAY INVISIBLE (-7150 4350);
FORCEADD RESISTOR..1
(-6850 6500);
FORCEPROP 1 LAST $LOCATION R37
J 2
(-7051 6505);
DISPLAY 1.212766 (-7051 6505);
PAINT GREEN (-7051 6505);
FORCEPROP 0 LAST CDS_LOCATION R37
J 0
(-6650 6600);
DISPLAY INVISIBLE (-6650 6600);
FORCEPROP 0 LAST $SEC 1
J 0
(-6650 6600);
DISPLAY 0.680851 (-6650 6600);
PAINT MONO (-6650 6600);
DISPLAY INVISIBLE (-6650 6600);
FORCEPROP 0 LAST CDS_SEC 1
J 0
(-6650 6600);
DISPLAY 1.021277 (-6650 6600);
DISPLAY INVISIBLE (-6650 6600);
FORCEPROP 0 LASTPIN (-6950 6500) $PN 1
J 2
(-6960 6510);
DISPLAY 0.680851 (-6960 6510);
PAINT MONO (-6960 6510);
FORCEPROP 0 LASTPIN (-6700 6500) $PN 2
J 0
(-6690 6510);
DISPLAY 0.680851 (-6690 6510);
PAINT MONO (-6690 6510);
FORCEPROP 1 LAST VALUE 0OHM
J 0
(-6600 6500);
DISPLAY 1.212766 (-6600 6500);
PAINT GREEN (-6600 6500);
FORCEPROP 0 LAST PACKAGE 0402
J 0
(-6900 6600);
DISPLAY 1.021277 (-6900 6600);
FORCEPROP 1 LAST PATH I25
J 0
(-7047 6605);
DISPLAY 1.212766 (-7047 6605);
PAINT GREEN (-7047 6605);
DISPLAY INVISIBLE (-7047 6605);
FORCEPROP 1 LAST TOLERANCE -
J 0
(-7047 6755);
DISPLAY 1.212766 (-7047 6755);
PAINT GREEN (-7047 6755);
DISPLAY INVISIBLE (-7047 6755);
FORCEPROP 1 LAST CLS_PN G155-100R0-J0
J 0
(-6986 6700);
DISPLAY 1.212766 (-6986 6700);
PAINT GREEN (-6986 6700);
DISPLAY INVISIBLE (-6986 6700);
FORCEPROP 2 LAST CDS_LIB passive
J 0
(-6850 6500);
DISPLAY INVISIBLE (-6850 6500);
FORCEPROP 1 LAST CDS_LMAN_SYM_OUTLINE -50,50,100,-50
J 0
(-6850 6500);
DISPLAY 0.468085 (-6850 6500);
PAINT GREEN (-6850 6500);
DISPLAY INVISIBLE (-6850 6500);
FORCEADD RESISTOR..2
(-5150 4600);
FORCEPROP 1 LAST $LOCATION R38
J 0
(-5100 4450);
DISPLAY 1.212766 (-5100 4450);
PAINT GREEN (-5100 4450);
FORCEPROP 0 LAST CDS_LOCATION R38
J 0
(-5100 4750);
DISPLAY 1.021277 (-5100 4750);
DISPLAY INVISIBLE (-5100 4750);
FORCEPROP 0 LAST $SEC 1
J 0
(-5100 4750);
DISPLAY 0.680851 (-5100 4750);
PAINT MONO (-5100 4750);
DISPLAY INVISIBLE (-5100 4750);
FORCEPROP 0 LAST CDS_SEC 1
J 0
(-5100 4750);
DISPLAY 1.021277 (-5100 4750);
DISPLAY INVISIBLE (-5100 4750);
FORCEPROP 0 LASTPIN (-5150 4700) $PN 1
R 1
J 0
(-5160 4710);
DISPLAY 0.680851 (-5160 4710);
PAINT MONO (-5160 4710);
FORCEPROP 0 LASTPIN (-5150 4450) $PN 2
R 1
J 2
(-5160 4440);
DISPLAY 0.680851 (-5160 4440);
PAINT MONO (-5160 4440);
FORCEPROP 0 LAST PACKAGE 0402
J 0
(-5100 4800);
DISPLAY 1.021277 (-5100 4800);
FORCEPROP 1 LAST VALUE 4.42KOHM
J 0
(-5100 4650);
DISPLAY 1.212766 (-5100 4650);
PAINT GREEN (-5100 4650);
FORCEPROP 1 LAST PATH I26
J 0
(-5347 4705);
DISPLAY 1.212766 (-5347 4705);
PAINT GREEN (-5347 4705);
DISPLAY INVISIBLE (-5347 4705);
FORCEPROP 1 LAST TOLERANCE 1%
J 0
(-5347 4855);
DISPLAY 1.212766 (-5347 4855);
PAINT GREEN (-5347 4855);
DISPLAY INVISIBLE (-5347 4855);
FORCEPROP 1 LAST CLS_PN G155-04421-01
J 0
(-5286 4800);
DISPLAY 1.212766 (-5286 4800);
PAINT GREEN (-5286 4800);
DISPLAY INVISIBLE (-5286 4800);
FORCEPROP 2 LAST CDS_LIB passive
J 0
(-5150 4600);
DISPLAY INVISIBLE (-5150 4600);
FORCEPROP 1 LAST CDS_LMAN_SYM_OUTLINE -50,50,50,-100
J 0
(-5150 4600);
DISPLAY 0.468085 (-5150 4600);
PAINT GREEN (-5150 4600);
DISPLAY INVISIBLE (-5150 4600);
FORCEADD CAPACITOR..1
(-5950 6500);
FORCEPROP 1 LAST $LOCATION C56
J 2
(-6088 6500);
DISPLAY 1.212766 (-6088 6500);
PAINT GREEN (-6088 6500);
FORCEPROP 0 LAST CDS_LOCATION C56
J 0
(-5200 6700);
DISPLAY INVISIBLE (-5200 6700);
FORCEPROP 0 LAST $SEC 1
J 0
(-5700 6650);
DISPLAY 0.680851 (-5700 6650);
PAINT MONO (-5700 6650);
DISPLAY INVISIBLE (-5700 6650);
FORCEPROP 0 LAST CDS_SEC 1
J 0
(-5700 6650);
DISPLAY 1.021277 (-5700 6650);
DISPLAY INVISIBLE (-5700 6650);
FORCEPROP 0 LASTPIN (-6050 6500) $PN 1
J 2
(-6060 6510);
DISPLAY 0.680851 (-6060 6510);
PAINT MONO (-6060 6510);
FORCEPROP 0 LASTPIN (-5800 6500) $PN 2
J 0
(-5790 6510);
DISPLAY 0.680851 (-5790 6510);
PAINT MONO (-5790 6510);
FORCEPROP 0 LAST VOLTAGE 25V
J 0
(-6000 6700);
DISPLAY 1.021277 (-6000 6700);
FORCEPROP 1 LAST VALUE 0.1UF
J 0
(-5700 6500);
DISPLAY 1.212766 (-5700 6500);
PAINT GREEN (-5700 6500);
FORCEPROP 0 LAST PACKAGE 0402
J 0
(-6000 6600);
DISPLAY 1.021277 (-6000 6600);
FORCEPROP 1 LAST PATH I27
J 2
(-6000 6600);
DISPLAY 1.212766 (-6000 6600);
PAINT GREEN (-6000 6600);
DISPLAY INVISIBLE (-6000 6600);
FORCEPROP 1 LAST TOLERANCE 10%
J 2
(-6050 6600);
DISPLAY 1.212766 (-6050 6600);
PAINT GREEN (-6050 6600);
DISPLAY INVISIBLE (-6050 6600);
FORCEPROP 1 LAST CDS_LMAN_SYM_OUTLINE 0,50,50,-50
J 0
(-5950 6500);
DISPLAY 0.468085 (-5950 6500);
PAINT GREEN (-5950 6500);
DISPLAY INVISIBLE (-5950 6500);
FORCEPROP 2 LAST CDS_LIB passive
J 0
(-5950 6500);
DISPLAY INVISIBLE (-5950 6500);
FORCEPROP 1 LAST CLS_PN G105-0B104-EK
J 2
(-6000 6600);
DISPLAY 1.212766 (-6000 6600);
PAINT GREEN (-6000 6600);
DISPLAY INVISIBLE (-6000 6600);
FORCEPROP 2 LASTPIN (-6050 6500) SIG_NAME UN$517$CAPACITOR$I27$1
J 0
(-6040 6510);
DISPLAY 0.659574 (-6040 6510);
PAINT MONO (-6040 6510);
DISPLAY INVISIBLE (-6040 6510);
FORCEADD INDUCTOR_2..1
(-4600 6300);
FORCEPROP 1 LAST $LOCATION L2
J 2
(-4800 6300);
DISPLAY 1.212766 (-4800 6300);
PAINT GREEN (-4800 6300);
FORCEPROP 0 LAST CDS_LOCATION L2
J 0
(-4350 6400);
DISPLAY INVISIBLE (-4350 6400);
FORCEPROP 0 LAST $SEC 1
J 0
(-4400 6450);
DISPLAY 0.680851 (-4400 6450);
PAINT MONO (-4400 6450);
DISPLAY INVISIBLE (-4400 6450);
FORCEPROP 0 LAST CDS_SEC 1
J 0
(-4400 6450);
DISPLAY 1.021277 (-4400 6450);
DISPLAY INVISIBLE (-4400 6450);
FORCEPROP 0 LASTPIN (-4750 6300) $PN 1
J 2
(-4760 6310);
DISPLAY 0.680851 (-4760 6310);
PAINT MONO (-4760 6310);
FORCEPROP 0 LASTPIN (-4400 6300) $PN 2
J 0
(-4390 6310);
DISPLAY 0.680851 (-4390 6310);
PAINT MONO (-4390 6310);
FORCEPROP 1 LAST VALUE 4.7UH
J 0
(-4350 6300);
DISPLAY 1.212766 (-4350 6300);
PAINT GREEN (-4350 6300);
FORCEPROP 1 LAST PATH I28
J 2
(-4648 6210);
DISPLAY 1.212766 (-4648 6210);
PAINT GREEN (-4648 6210);
DISPLAY INVISIBLE (-4648 6210);
FORCEPROP 1 LAST CLS_PN G190-10424-01
J 2
(-4644 6450);
DISPLAY 1.212766 (-4644 6450);
PAINT GREEN (-4644 6450);
DISPLAY INVISIBLE (-4644 6450);
FORCEPROP 1 LAST CDS_LMAN_SYM_OUTLINE -100,50,150,-50
J 0
(-4600 6300);
DISPLAY 0.468085 (-4600 6300);
PAINT GREEN (-4600 6300);
DISPLAY INVISIBLE (-4600 6300);
FORCEPROP 2 LAST CDS_LIB passive
J 0
(-4600 6300);
DISPLAY INVISIBLE (-4600 6300);
FORCEPROP 1 LAST TOLERANCE 20%
J 2
(-4394 6200);
DISPLAY 1.212766 (-4394 6200);
PAINT GREEN (-4394 6200);
DISPLAY INVISIBLE (-4394 6200);
FORCEADD CAPACITOR..1
(-4650 6650);
FORCEPROP 1 LAST $LOCATION C57
J 2
(-4750 6650);
DISPLAY 1.212766 (-4750 6650);
PAINT GREEN (-4750 6650);
FORCEPROP 0 LAST CDS_LOCATION C57
J 0
(-3400 6750);
DISPLAY INVISIBLE (-3400 6750);
FORCEPROP 0 LAST $SEC 1
J 0
(-4400 6800);
DISPLAY 0.680851 (-4400 6800);
PAINT MONO (-4400 6800);
DISPLAY INVISIBLE (-4400 6800);
FORCEPROP 0 LAST CDS_SEC 1
J 0
(-4400 6800);
DISPLAY 1.021277 (-4400 6800);
DISPLAY INVISIBLE (-4400 6800);
FORCEPROP 0 LASTPIN (-4750 6650) $PN 1
J 2
(-4760 6660);
DISPLAY 0.680851 (-4760 6660);
PAINT MONO (-4760 6660);
FORCEPROP 0 LASTPIN (-4500 6650) $PN 2
J 0
(-4490 6660);
DISPLAY 0.680851 (-4490 6660);
PAINT MONO (-4490 6660);
FORCEPROP 0 LAST VOLTAGE 50V
J 0
(-4700 6850);
DISPLAY 1.021277 (-4700 6850);
FORCEPROP 0 LAST NO_ASSY TRUE
J 0
(-4800 6500);
DISPLAY 1.021277 (-4800 6500);
DISPLAY BOTH (-4800 6500);
FORCEPROP 0 LAST PACKAGE 0402
J 0
(-4700 6750);
DISPLAY 1.021277 (-4700 6750);
FORCEPROP 1 LAST VALUE 1000PF
J 0
(-4350 6650);
DISPLAY 1.212766 (-4350 6650);
PAINT GREEN (-4350 6650);
FORCEPROP 1 LAST PATH I29
J 2
(-4700 6750);
DISPLAY 1.212766 (-4700 6750);
PAINT GREEN (-4700 6750);
DISPLAY INVISIBLE (-4700 6750);
FORCEPROP 1 LAST TOLERANCE 5%
J 2
(-4750 6750);
DISPLAY 1.212766 (-4750 6750);
PAINT GREEN (-4750 6750);
DISPLAY INVISIBLE (-4750 6750);
FORCEPROP 2 LASTPIN (-4500 6650) SIG_NAME UN$517$CAPACITOR$I29$2
J 0
(-4490 6660);
DISPLAY 0.659574 (-4490 6660);
PAINT MONO (-4490 6660);
DISPLAY INVISIBLE (-4490 6660);
FORCEPROP 2 LAST CDS_LIB passive
J 0
(-4650 6650);
DISPLAY INVISIBLE (-4650 6650);
FORCEPROP 1 LAST CDS_LMAN_SYM_OUTLINE 0,50,50,-50
J 0
(-4650 6650);
DISPLAY 0.468085 (-4650 6650);
PAINT GREEN (-4650 6650);
DISPLAY INVISIBLE (-4650 6650);
FORCEPROP 1 LAST CLS_PN G105-0A102-FJ
J 2
(-4700 6750);
DISPLAY 1.212766 (-4700 6750);
PAINT GREEN (-4700 6750);
DISPLAY INVISIBLE (-4700 6750);
FORCEADD RESISTOR..2
(-13000 4450);
FORCEPROP 1 LAST $LOCATION R51
J 0
(-12950 4300);
DISPLAY 1.212766 (-12950 4300);
PAINT GREEN (-12950 4300);
FORCEPROP 0 LAST CDS_LOCATION R51
J 0
(-12950 4650);
DISPLAY 1.021277 (-12950 4650);
DISPLAY INVISIBLE (-12950 4650);
FORCEPROP 0 LAST $SEC 1
J 0
(-12950 4650);
DISPLAY 0.680851 (-12950 4650);
PAINT MONO (-12950 4650);
DISPLAY INVISIBLE (-12950 4650);
FORCEPROP 0 LAST CDS_SEC 1
J 0
(-12950 4650);
DISPLAY 1.021277 (-12950 4650);
DISPLAY INVISIBLE (-12950 4650);
FORCEPROP 0 LASTPIN (-13000 4550) $PN 1
R 1
J 0
(-13010 4560);
DISPLAY 0.680851 (-13010 4560);
PAINT MONO (-13010 4560);
FORCEPROP 0 LASTPIN (-13000 4300) $PN 2
R 1
J 2
(-13010 4290);
DISPLAY 0.680851 (-13010 4290);
PAINT MONO (-13010 4290);
FORCEPROP 0 LAST PACKAGE 0402
J 0
(-12900 4450);
DISPLAY 1.021277 (-12900 4450);
FORCEPROP 1 LAST VALUE 10KOHM
J 0
(-12950 4550);
DISPLAY 1.212766 (-12950 4550);
PAINT GREEN (-12950 4550);
FORCEPROP 1 LAST PATH I3
J 0
(-13197 4555);
DISPLAY 1.212766 (-13197 4555);
PAINT GREEN (-13197 4555);
DISPLAY INVISIBLE (-13197 4555);
FORCEPROP 1 LAST TOLERANCE 1%
J 0
(-13197 4705);
DISPLAY 1.212766 (-13197 4705);
PAINT GREEN (-13197 4705);
DISPLAY INVISIBLE (-13197 4705);
FORCEPROP 1 LAST CLS_PN G155-11002-01
J 0
(-13136 4650);
DISPLAY 1.212766 (-13136 4650);
PAINT GREEN (-13136 4650);
DISPLAY INVISIBLE (-13136 4650);
FORCEPROP 2 LAST CDS_LIB passive
J 0
(-13000 4450);
DISPLAY INVISIBLE (-13000 4450);
FORCEPROP 1 LAST CDS_LMAN_SYM_OUTLINE -50,50,50,-100
J 0
(-13000 4450);
DISPLAY 0.468085 (-13000 4450);
PAINT GREEN (-13000 4450);
DISPLAY INVISIBLE (-13000 4450);
FORCEADD CAPACITOR..2
(-3750 5300);
FORCEPROP 1 LAST $LOCATION C16
J 0
(-3650 5400);
DISPLAY 1.212766 (-3650 5400);
PAINT GREEN (-3650 5400);
FORCEPROP 0 LAST CDS_LOCATION C16
J 0
(-3650 5550);
DISPLAY INVISIBLE (-3650 5550);
FORCEPROP 0 LAST $SEC 1
J 0
(-3700 5450);
DISPLAY 0.680851 (-3700 5450);
PAINT MONO (-3700 5450);
DISPLAY INVISIBLE (-3700 5450);
FORCEPROP 0 LAST CDS_SEC 1
J 0
(-3700 5450);
DISPLAY 1.021277 (-3700 5450);
DISPLAY INVISIBLE (-3700 5450);
FORCEPROP 0 LASTPIN (-3750 5400) $PN 1
R 1
J 0
(-3760 5410);
DISPLAY 0.680851 (-3760 5410);
PAINT MONO (-3760 5410);
FORCEPROP 0 LASTPIN (-3750 5150) $PN 2
R 1
J 2
(-3760 5140);
DISPLAY 0.680851 (-3760 5140);
PAINT MONO (-3760 5140);
FORCEPROP 1 LAST VALUE 100PF
J 0
(-3650 5300);
DISPLAY 1.212766 (-3650 5300);
PAINT GREEN (-3650 5300);
FORCEPROP 0 LAST PACKAGE 0201
J 0
(-3650 5200);
DISPLAY 1.021277 (-3650 5200);
FORCEPROP 0 LAST VOLTAGE 50V
J 0
(-3650 5100);
DISPLAY 1.021277 (-3650 5100);
FORCEPROP 1 LAST PATH I30
J 0
(-3850 5350);
DISPLAY 1.212766 (-3850 5350);
PAINT GREEN (-3850 5350);
DISPLAY INVISIBLE (-3850 5350);
FORCEPROP 1 LAST TOLERANCE 10%
J 0
(-3900 5400);
DISPLAY 1.212766 (-3900 5400);
PAINT GREEN (-3900 5400);
DISPLAY INVISIBLE (-3900 5400);
FORCEPROP 1 LAST CDS_LMAN_SYM_OUTLINE -50,0,50,-50
J 0
(-3750 5300);
DISPLAY 0.468085 (-3750 5300);
PAINT GREEN (-3750 5300);
DISPLAY INVISIBLE (-3750 5300);
FORCEPROP 2 LAST CDS_LIB passive
J 0
(-3750 5300);
DISPLAY INVISIBLE (-3750 5300);
FORCEPROP 1 LAST CLS_PN G104-0B101-FK
J 0
(-3850 5350);
DISPLAY 1.212766 (-3850 5350);
PAINT GREEN (-3850 5350);
DISPLAY INVISIBLE (-3850 5350);
FORCEPROP 2 LASTPIN (-3750 5400) SIG_NAME UN$517$CAPACITOR$I30$1
J 0
(-3740 5410);
DISPLAY 0.659574 (-3740 5410);
PAINT MONO (-3740 5410);
DISPLAY INVISIBLE (-3740 5410);
FORCEADD RESISTOR..2
(-3100 5350);
FORCEPROP 1 LAST $LOCATION R40
J 0
(-3050 5200);
DISPLAY 1.212766 (-3050 5200);
PAINT GREEN (-3050 5200);
FORCEPROP 0 LAST CDS_LOCATION R40
J 0
(-3050 5500);
DISPLAY INVISIBLE (-3050 5500);
FORCEPROP 0 LAST $SEC 1
J 0
(-3050 5500);
DISPLAY 0.680851 (-3050 5500);
PAINT MONO (-3050 5500);
DISPLAY INVISIBLE (-3050 5500);
FORCEPROP 0 LAST CDS_SEC 1
J 0
(-3050 5500);
DISPLAY 1.021277 (-3050 5500);
DISPLAY INVISIBLE (-3050 5500);
FORCEPROP 0 LASTPIN (-3100 5450) $PN 1
R 1
J 0
(-3110 5460);
DISPLAY 0.680851 (-3110 5460);
PAINT MONO (-3110 5460);
FORCEPROP 0 LASTPIN (-3100 5200) $PN 2
R 1
J 2
(-3110 5190);
DISPLAY 0.680851 (-3110 5190);
PAINT MONO (-3110 5190);
FORCEPROP 1 LAST VALUE 20KOHM
J 0
(-3050 5400);
DISPLAY 1.212766 (-3050 5400);
PAINT GREEN (-3050 5400);
FORCEPROP 0 LAST PACKAGE 0402
J 0
(-3050 5550);
DISPLAY 1.021277 (-3050 5550);
FORCEPROP 1 LAST PATH I31
J 0
(-3297 5455);
DISPLAY 1.212766 (-3297 5455);
PAINT GREEN (-3297 5455);
DISPLAY INVISIBLE (-3297 5455);
FORCEPROP 1 LAST TOLERANCE 1%
J 0
(-3297 5605);
DISPLAY 1.212766 (-3297 5605);
PAINT GREEN (-3297 5605);
DISPLAY INVISIBLE (-3297 5605);
FORCEPROP 1 LAST CLS_PN G155-12002-01
J 0
(-3236 5550);
DISPLAY 1.212766 (-3236 5550);
PAINT GREEN (-3236 5550);
DISPLAY INVISIBLE (-3236 5550);
FORCEPROP 1 LAST CDS_LMAN_SYM_OUTLINE -50,50,50,-100
J 0
(-3100 5350);
DISPLAY 0.468085 (-3100 5350);
PAINT GREEN (-3100 5350);
DISPLAY INVISIBLE (-3100 5350);
FORCEPROP 2 LAST CDS_LIB passive
J 0
(-3100 5350);
DISPLAY INVISIBLE (-3100 5350);
FORCEADD RESISTOR..1
(-3650 6650);
FORCEPROP 1 LAST $LOCATION R39
J 2
(-3850 6650);
DISPLAY 1.212766 (-3850 6650);
PAINT GREEN (-3850 6650);
FORCEPROP 0 LAST CDS_LOCATION R39
J 0
(-3400 6750);
DISPLAY INVISIBLE (-3400 6750);
FORCEPROP 0 LAST $SEC 1
J 0
(-3500 6800);
DISPLAY 0.680851 (-3500 6800);
PAINT MONO (-3500 6800);
DISPLAY INVISIBLE (-3500 6800);
FORCEPROP 0 LAST CDS_SEC 1
J 0
(-3500 6800);
DISPLAY 1.021277 (-3500 6800);
DISPLAY INVISIBLE (-3500 6800);
FORCEPROP 0 LASTPIN (-3750 6650) $PN 1
J 2
(-3760 6660);
DISPLAY 0.680851 (-3760 6660);
PAINT MONO (-3760 6660);
FORCEPROP 0 LASTPIN (-3500 6650) $PN 2
J 0
(-3490 6660);
DISPLAY 0.680851 (-3490 6660);
PAINT MONO (-3490 6660);
FORCEPROP 0 LAST NO_ASSY TRUE
J 0
(-3850 6500);
DISPLAY 1.021277 (-3850 6500);
DISPLAY BOTH (-3850 6500);
FORCEPROP 1 LAST VALUE 2.2OHM
J 0
(-3400 6650);
DISPLAY 1.212766 (-3400 6650);
PAINT GREEN (-3400 6650);
FORCEPROP 0 LAST PACKAGE 0805
J 0
(-3700 6700);
DISPLAY 1.021277 (-3700 6700);
FORCEPROP 1 LAST PATH I32
J 0
(-3847 6755);
DISPLAY 1.212766 (-3847 6755);
PAINT GREEN (-3847 6755);
DISPLAY INVISIBLE (-3847 6755);
FORCEPROP 1 LAST TOLERANCE 1%
J 0
(-3847 6905);
DISPLAY 1.212766 (-3847 6905);
PAINT GREEN (-3847 6905);
DISPLAY INVISIBLE (-3847 6905);
FORCEPROP 1 LAST CDS_LMAN_SYM_OUTLINE -50,50,100,-50
J 0
(-3650 6650);
DISPLAY 0.468085 (-3650 6650);
PAINT GREEN (-3650 6650);
DISPLAY INVISIBLE (-3650 6650);
FORCEPROP 2 LAST CDS_LIB passive
J 0
(-3650 6650);
DISPLAY INVISIBLE (-3650 6650);
FORCEPROP 1 LAST CLS_PN G157-12R20-01
J 0
(-3786 6850);
DISPLAY 1.212766 (-3786 6850);
PAINT GREEN (-3786 6850);
DISPLAY INVISIBLE (-3786 6850);
FORCEADD RESISTOR..2
(-3100 5900);
FORCEPROP 1 LAST $LOCATION R17
J 0
(-3050 5750);
DISPLAY 1.212766 (-3050 5750);
PAINT GREEN (-3050 5750);
FORCEPROP 0 LAST CDS_LOCATION R17
J 0
(-3050 6050);
DISPLAY INVISIBLE (-3050 6050);
FORCEPROP 0 LAST $SEC 1
J 0
(-3050 6050);
DISPLAY 0.680851 (-3050 6050);
PAINT MONO (-3050 6050);
DISPLAY INVISIBLE (-3050 6050);
FORCEPROP 0 LAST CDS_SEC 1
J 0
(-3050 6050);
DISPLAY 1.021277 (-3050 6050);
DISPLAY INVISIBLE (-3050 6050);
FORCEPROP 0 LASTPIN (-3100 6000) $PN 1
R 1
J 0
(-3110 6010);
DISPLAY 0.680851 (-3110 6010);
PAINT MONO (-3110 6010);
FORCEPROP 0 LASTPIN (-3100 5750) $PN 2
R 1
J 2
(-3110 5740);
DISPLAY 0.680851 (-3110 5740);
PAINT MONO (-3110 5740);
FORCEPROP 1 LAST VALUE 20OHM
J 0
(-3050 5950);
DISPLAY 1.212766 (-3050 5950);
PAINT GREEN (-3050 5950);
FORCEPROP 0 LAST PACKAGE 0402
J 0
(-3050 6100);
DISPLAY 1.021277 (-3050 6100);
FORCEPROP 1 LAST PATH I33
J 0
(-3297 6005);
DISPLAY 1.212766 (-3297 6005);
PAINT GREEN (-3297 6005);
DISPLAY INVISIBLE (-3297 6005);
FORCEPROP 1 LAST TOLERANCE 1%
J 0
(-3297 6155);
DISPLAY 1.212766 (-3297 6155);
PAINT GREEN (-3297 6155);
DISPLAY INVISIBLE (-3297 6155);
FORCEPROP 1 LAST CDS_LMAN_SYM_OUTLINE -50,50,50,-100
J 0
(-3100 5900);
DISPLAY 0.468085 (-3100 5900);
PAINT GREEN (-3100 5900);
DISPLAY INVISIBLE (-3100 5900);
FORCEPROP 2 LAST CDS_LIB passive
J 0
(-3100 5900);
DISPLAY INVISIBLE (-3100 5900);
FORCEPROP 1 LAST CLS_PN G155-120R0-01
J 0
(-3236 6100);
DISPLAY 1.212766 (-3236 6100);
PAINT GREEN (-3236 6100);
DISPLAY INVISIBLE (-3236 6100);
FORCEADD GND_SG..1
(-3200 6500);
FORCEPROP 3 LASTPIN (-3150 6550) SIG_NAME SG\g
J 0
(-3140 6560);
DISPLAY 0.659574 (-3140 6560);
PAINT MONO (-3140 6560);
DISPLAY INVISIBLE (-3140 6560);
FORCEPROP 1 LAST HDL_POWER SG
J 1
(-3145 6405);
DISPLAY 0.808511 (-3145 6405);
PAINT GREEN (-3145 6405);
FORCEPROP 1 LAST PATH I34
J 0
(-3165 6500);
DISPLAY 0.808511 (-3165 6500);
PAINT GREEN (-3165 6500);
DISPLAY INVISIBLE (-3165 6500);
FORCEPROP 1 LAST BODY_TYPE PLUMBING
J 0
(-3185 6485);
DISPLAY 0.808511 (-3185 6485);
PAINT GREEN (-3185 6485);
DISPLAY INVISIBLE (-3185 6485);
FORCEPROP 2 LAST CDS_LIB cls
J 0
(-3200 6500);
DISPLAY INVISIBLE (-3200 6500);
FORCEPROP 1 LAST CDS_LMAN_SYM_OUTLINE 0,0,100,-50
J 0
(-3200 6500);
DISPLAY 0.468085 (-3200 6500);
PAINT GREEN (-3200 6500);
DISPLAY INVISIBLE (-3200 6500);
FORCEADD GND_SG..1
(-1100 5250);
FORCEPROP 3 LASTPIN (-1050 5300) SIG_NAME SG\g
J 0
(-1040 5310);
DISPLAY 0.659574 (-1040 5310);
PAINT MONO (-1040 5310);
DISPLAY INVISIBLE (-1040 5310);
FORCEPROP 1 LAST HDL_POWER SG
J 1
(-1045 5155);
DISPLAY 0.808511 (-1045 5155);
PAINT GREEN (-1045 5155);
FORCEPROP 1 LAST PATH I35
J 0
(-1065 5250);
DISPLAY 0.808511 (-1065 5250);
PAINT GREEN (-1065 5250);
DISPLAY INVISIBLE (-1065 5250);
FORCEPROP 1 LAST BODY_TYPE PLUMBING
J 0
(-1085 5235);
DISPLAY 0.808511 (-1085 5235);
PAINT GREEN (-1085 5235);
DISPLAY INVISIBLE (-1085 5235);
FORCEPROP 2 LAST CDS_LIB cls
J 0
(-1100 5250);
DISPLAY INVISIBLE (-1100 5250);
FORCEPROP 1 LAST CDS_LMAN_SYM_OUTLINE 0,0,100,-50
J 0
(-1100 5250);
DISPLAY 0.468085 (-1100 5250);
PAINT GREEN (-1100 5250);
DISPLAY INVISIBLE (-1100 5250);
FORCEADD CAPACITOR..2
(-2500 5950);
FORCEPROP 1 LAST $LOCATION C18
J 0
(-2400 6000);
DISPLAY 1.212766 (-2400 6000);
PAINT GREEN (-2400 6000);
FORCEPROP 0 LAST CDS_LOCATION C18
J 0
(-2400 6200);
DISPLAY INVISIBLE (-2400 6200);
FORCEPROP 0 LAST $SEC 1
J 0
(-2450 6100);
DISPLAY 0.680851 (-2450 6100);
PAINT MONO (-2450 6100);
DISPLAY INVISIBLE (-2450 6100);
FORCEPROP 0 LAST CDS_SEC 1
J 0
(-2450 6100);
DISPLAY 1.021277 (-2450 6100);
DISPLAY INVISIBLE (-2450 6100);
FORCEPROP 0 LASTPIN (-2500 6050) $PN 1
R 1
J 0
(-2510 6060);
DISPLAY 0.680851 (-2510 6060);
PAINT MONO (-2510 6060);
FORCEPROP 0 LASTPIN (-2500 5800) $PN 2
R 1
J 2
(-2510 5790);
DISPLAY 0.680851 (-2510 5790);
PAINT MONO (-2510 5790);
FORCEPROP 0 LAST VOLTAGE 10V
J 0
(-2400 6250);
DISPLAY 1.021277 (-2400 6250);
FORCEPROP 0 LAST PACKAGE 0402
J 0
(-2400 6150);
DISPLAY 1.021277 (-2400 6150);
FORCEPROP 1 LAST VALUE 0.1UF
J 0
(-2400 5900);
DISPLAY 1.212766 (-2400 5900);
PAINT GREEN (-2400 5900);
FORCEPROP 1 LAST PATH I36
J 0
(-2600 6000);
DISPLAY 1.212766 (-2600 6000);
PAINT GREEN (-2600 6000);
DISPLAY INVISIBLE (-2600 6000);
FORCEPROP 1 LAST TOLERANCE 10%
J 0
(-2650 6050);
DISPLAY 1.212766 (-2650 6050);
PAINT GREEN (-2650 6050);
DISPLAY INVISIBLE (-2650 6050);
FORCEPROP 1 LAST CDS_LMAN_SYM_OUTLINE -50,0,50,-50
J 0
(-2500 5950);
DISPLAY 0.468085 (-2500 5950);
PAINT GREEN (-2500 5950);
DISPLAY INVISIBLE (-2500 5950);
FORCEPROP 2 LAST CDS_LIB passive
J 0
(-2500 5950);
DISPLAY INVISIBLE (-2500 5950);
FORCEPROP 1 LAST CLS_PN G105-0B104-CK
J 0
(-2600 6000);
DISPLAY 1.212766 (-2600 6000);
PAINT GREEN (-2600 6000);
DISPLAY INVISIBLE (-2600 6000);
FORCEADD CAPACITOR..2
(-2000 5950);
FORCEPROP 1 LAST $LOCATION C20
J 0
(-1900 6000);
DISPLAY 1.212766 (-1900 6000);
PAINT GREEN (-1900 6000);
FORCEPROP 0 LAST CDS_LOCATION C20
J 0
(-1900 6200);
DISPLAY INVISIBLE (-1900 6200);
FORCEPROP 0 LAST $SEC 1
J 0
(-1950 6100);
DISPLAY INVISIBLE (-1950 6100);
FORCEPROP 0 LAST CDS_SEC 1
J 0
(-1950 6100);
DISPLAY INVISIBLE (-1950 6100);
FORCEPROP 0 LASTPIN (-2000 6050) $PN 1
R 1
J 0
(-2010 6060);
DISPLAY 0.808511 (-2010 6060);
FORCEPROP 0 LASTPIN (-2000 5800) $PN 2
R 1
J 2
(-2010 5790);
DISPLAY 0.808511 (-2010 5790);
FORCEPROP 0 LAST VOLTAGE 10V
J 0
(-1900 6250);
DISPLAY 1.021277 (-1900 6250);
FORCEPROP 0 LAST PACKAGE 0805
J 0
(-1900 6150);
DISPLAY 1.021277 (-1900 6150);
FORCEPROP 1 LAST VALUE 22UF
J 0
(-1900 5900);
DISPLAY 1.212766 (-1900 5900);
PAINT GREEN (-1900 5900);
FORCEPROP 1 LAST PATH I37
J 0
(-2100 6000);
DISPLAY 1.212766 (-2100 6000);
PAINT GREEN (-2100 6000);
DISPLAY INVISIBLE (-2100 6000);
FORCEPROP 1 LAST CLS_PN G107-0F226-CM
J 0
(-2100 6000);
DISPLAY 1.212766 (-2100 6000);
PAINT GREEN (-2100 6000);
DISPLAY INVISIBLE (-2100 6000);
FORCEPROP 2 LAST CDS_LIB passive
J 0
(-2000 5950);
DISPLAY INVISIBLE (-2000 5950);
FORCEPROP 1 LAST CDS_LMAN_SYM_OUTLINE -50,0,50,-50
J 0
(-2000 5950);
DISPLAY 0.468085 (-2000 5950);
PAINT GREEN (-2000 5950);
DISPLAY INVISIBLE (-2000 5950);
FORCEPROP 1 LAST TOLERANCE 20%
J 0
(-2150 6050);
DISPLAY 1.212766 (-2150 6050);
PAINT GREEN (-2150 6050);
DISPLAY INVISIBLE (-2150 6050);
FORCEADD CAPACITOR..2
(-1500 5950);
FORCEPROP 1 LAST $LOCATION C21
J 0
(-1400 6000);
DISPLAY 1.212766 (-1400 6000);
PAINT GREEN (-1400 6000);
FORCEPROP 0 LAST CDS_LOCATION C21
J 0
(-1400 6200);
DISPLAY INVISIBLE (-1400 6200);
FORCEPROP 0 LAST $SEC 1
J 0
(-1450 6100);
DISPLAY INVISIBLE (-1450 6100);
FORCEPROP 0 LAST CDS_SEC 1
J 0
(-1450 6100);
DISPLAY INVISIBLE (-1450 6100);
FORCEPROP 0 LASTPIN (-1500 6050) $PN 1
R 1
J 0
(-1510 6060);
DISPLAY 0.808511 (-1510 6060);
FORCEPROP 0 LASTPIN (-1500 5800) $PN 2
R 1
J 2
(-1510 5790);
DISPLAY 0.808511 (-1510 5790);
FORCEPROP 0 LAST VOLTAGE 10V
J 0
(-1400 6250);
DISPLAY 1.021277 (-1400 6250);
FORCEPROP 1 LAST VALUE 22UF
J 0
(-1400 5900);
DISPLAY 1.212766 (-1400 5900);
PAINT GREEN (-1400 5900);
FORCEPROP 0 LAST PACKAGE 0805
J 0
(-1400 6150);
DISPLAY 1.021277 (-1400 6150);
FORCEPROP 1 LAST PATH I38
J 0
(-1600 6000);
DISPLAY 1.212766 (-1600 6000);
PAINT GREEN (-1600 6000);
DISPLAY INVISIBLE (-1600 6000);
FORCEPROP 1 LAST CLS_PN G107-0F226-CM
J 0
(-1600 6000);
DISPLAY 1.212766 (-1600 6000);
PAINT GREEN (-1600 6000);
DISPLAY INVISIBLE (-1600 6000);
FORCEPROP 2 LAST CDS_LIB passive
J 0
(-1500 5950);
DISPLAY INVISIBLE (-1500 5950);
FORCEPROP 1 LAST CDS_LMAN_SYM_OUTLINE -50,0,50,-50
J 0
(-1500 5950);
DISPLAY 0.468085 (-1500 5950);
PAINT GREEN (-1500 5950);
DISPLAY INVISIBLE (-1500 5950);
FORCEPROP 1 LAST TOLERANCE 20%
J 0
(-1650 6050);
DISPLAY 1.212766 (-1650 6050);
PAINT GREEN (-1650 6050);
DISPLAY INVISIBLE (-1650 6050);
FORCEADD VCC..1
(-1100 6700);
FORCEPROP 3 LASTPIN (-1050 6650) SIG_NAME XP3R3V\g
J 0
(-1040 6660);
DISPLAY 0.659574 (-1040 6660);
PAINT MONO (-1040 6660);
DISPLAY INVISIBLE (-1040 6660);
FORCEPROP 1 LAST HDL_POWER XP3R3V
J 1
(-1045 6755);
DISPLAY 1.021277 (-1045 6755);
PAINT GREEN (-1045 6755);
FORCEPROP 0 LAST VOLTAGE 3.3
J 0
(-1250 6850);
DISPLAY 1.021277 (-1250 6850);
DISPLAY BOTH (-1250 6850);
FORCEPROP 1 LAST PATH I39
J 0
(-1065 6790);
DISPLAY 0.808511 (-1065 6790);
PAINT GREEN (-1065 6790);
DISPLAY INVISIBLE (-1065 6790);
FORCEPROP 1 LAST BODY_TYPE PLUMBING
J 0
(-1145 6657);
DISPLAY 0.340426 (-1145 6657);
PAINT GREEN (-1145 6657);
DISPLAY INVISIBLE (-1145 6657);
FORCEPROP 2 LAST CDS_LIB cls
J 0
(-1100 6700);
DISPLAY INVISIBLE (-1100 6700);
FORCEPROP 1 LAST CDS_LMAN_SYM_OUTLINE -250,250,250,-250
J 0
(-1100 6700);
DISPLAY 0.468085 (-1100 6700);
PAINT GREEN (-1100 6700);
DISPLAY INVISIBLE (-1100 6700);
FORCEADD CAPACITOR..2
(-1050 5950);
FORCEPROP 1 LAST $LOCATION C22
J 0
(-950 6000);
DISPLAY 1.212766 (-950 6000);
PAINT GREEN (-950 6000);
FORCEPROP 0 LAST CDS_LOCATION C22
J 0
(-950 6200);
DISPLAY INVISIBLE (-950 6200);
FORCEPROP 0 LAST $SEC 1
J 0
(-950 6200);
DISPLAY INVISIBLE (-950 6200);
FORCEPROP 0 LAST CDS_SEC 1
J 0
(-950 6200);
DISPLAY INVISIBLE (-950 6200);
FORCEPROP 0 LASTPIN (-1050 6050) $PN 1
R 1
J 0
(-1060 6060);
DISPLAY 0.808511 (-1060 6060);
FORCEPROP 0 LASTPIN (-1050 5800) $PN 2
R 1
J 2
(-1060 5790);
DISPLAY 0.808511 (-1060 5790);
FORCEPROP 0 LAST VOLTAGE 10V
J 0
(-950 6250);
DISPLAY 1.021277 (-950 6250);
FORCEPROP 1 LAST VALUE 22UF
J 0
(-950 5900);
DISPLAY 1.212766 (-950 5900);
PAINT GREEN (-950 5900);
FORCEPROP 0 LAST PACKAGE 0805
J 0
(-950 6150);
DISPLAY 1.021277 (-950 6150);
FORCEPROP 1 LAST PATH I40
J 0
(-1150 6000);
DISPLAY 1.212766 (-1150 6000);
PAINT GREEN (-1150 6000);
DISPLAY INVISIBLE (-1150 6000);
FORCEPROP 1 LAST CLS_PN G107-0F226-CM
J 0
(-1150 6000);
DISPLAY 1.212766 (-1150 6000);
PAINT GREEN (-1150 6000);
DISPLAY INVISIBLE (-1150 6000);
FORCEPROP 1 LAST CDS_LMAN_SYM_OUTLINE -50,0,50,-50
J 0
(-1050 5950);
DISPLAY 0.468085 (-1050 5950);
PAINT GREEN (-1050 5950);
DISPLAY INVISIBLE (-1050 5950);
FORCEPROP 2 LAST CDS_LIB passive
J 0
(-1050 5950);
DISPLAY INVISIBLE (-1050 5950);
FORCEPROP 1 LAST TOLERANCE 20%
J 0
(-1200 6050);
DISPLAY 1.212766 (-1200 6050);
PAINT GREEN (-1200 6050);
DISPLAY INVISIBLE (-1200 6050);
FORCEADD RESISTOR..1
R 1
(-4550 4550);
FORCEPROP 1 LAST $LOCATION R54
R 1
J 2
(-4605 4449);
DISPLAY 1.212766 (-4605 4449);
PAINT GREEN (-4605 4449);
FORCEPROP 0 LAST CDS_LOCATION R54
R 1
J 0
(-4400 4650);
DISPLAY 1.021277 (-4400 4650);
DISPLAY INVISIBLE (-4400 4650);
FORCEPROP 0 LAST $SEC 1
R 1
J 0
(-4400 4650);
DISPLAY 0.680851 (-4400 4650);
PAINT MONO (-4400 4650);
DISPLAY INVISIBLE (-4400 4650);
FORCEPROP 0 LAST CDS_SEC 1
R 1
J 0
(-4400 4650);
DISPLAY 1.021277 (-4400 4650);
DISPLAY INVISIBLE (-4400 4650);
FORCEPROP 0 LASTPIN (-4550 4450) $PN 1
R 1
J 2
(-4560 4440);
DISPLAY 0.680851 (-4560 4440);
PAINT MONO (-4560 4440);
FORCEPROP 0 LASTPIN (-4550 4700) $PN 2
R 1
J 0
(-4560 4710);
DISPLAY 0.680851 (-4560 4710);
PAINT MONO (-4560 4710);
FORCEPROP 1 LAST VALUE 0OHM
R 1
J 0
(-4450 4500);
DISPLAY 1.212766 (-4450 4500);
PAINT GREEN (-4450 4500);
FORCEPROP 0 LAST NO_ASSY TRUE
J 0
(-4400 4600);
DISPLAY 1.021277 (-4400 4600);
DISPLAY BOTH (-4400 4600);
FORCEPROP 0 LAST PACKAGE 0603
R 1
J 0
(-4350 4350);
DISPLAY 1.021277 (-4350 4350);
FORCEPROP 1 LAST PATH I41
R 1
J 0
(-4655 4353);
DISPLAY 1.212766 (-4655 4353);
PAINT GREEN (-4655 4353);
DISPLAY INVISIBLE (-4655 4353);
FORCEPROP 1 LAST TOLERANCE -
R 1
J 0
(-4805 4353);
DISPLAY 1.212766 (-4805 4353);
PAINT GREEN (-4805 4353);
DISPLAY INVISIBLE (-4805 4353);
FORCEPROP 1 LAST CLS_PN G156-100R0-J0
R 1
J 0
(-4750 4414);
DISPLAY 1.212766 (-4750 4414);
PAINT GREEN (-4750 4414);
DISPLAY INVISIBLE (-4750 4414);
FORCEPROP 1 LAST CDS_LMAN_SYM_OUTLINE -50,50,100,-50
R 1
J 0
(-4550 4550);
DISPLAY 0.468085 (-4550 4550);
PAINT GREEN (-4550 4550);
DISPLAY INVISIBLE (-4550 4550);
FORCEPROP 2 LAST CDS_LIB passive
J 0
(-4550 4550);
DISPLAY INVISIBLE (-4550 4550);
FORCEADD TPS54824RNVR_VQFN18..1
(-9200 6600);
FORCEPROP 1 LAST $LOCATION U6
J 0
(-9150 6700);
DISPLAY 1.212766 (-9150 6700);
PAINT GREEN (-9150 6700);
FORCEPROP 0 LAST CDS_LOCATION U6
J 0
(-9150 6700);
DISPLAY 1.212766 (-9150 6700);
PAINT GREEN (-9150 6700);
DISPLAY INVISIBLE (-9150 6700);
FORCEPROP 0 LAST $SEC 1
J 0
(-9150 7000);
DISPLAY 0.680851 (-9150 7000);
PAINT MONO (-9150 7000);
DISPLAY INVISIBLE (-9150 7000);
FORCEPROP 0 LAST CDS_SEC 1
J 0
(-9150 7000);
DISPLAY 1.021277 (-9150 7000);
DISPLAY INVISIBLE (-9150 7000);
FORCEPROP 0 LASTPIN (-9300 5000) $PN 12
J 2
(-9310 5010);
DISPLAY 0.680851 (-9310 5010);
PAINT MONO (-9310 5010);
FORCEPROP 0 LASTPIN (-8100 6500) $PN 1
J 0
(-8090 6510);
DISPLAY 0.680851 (-8090 6510);
PAINT MONO (-8090 6510);
FORCEPROP 0 LASTPIN (-9300 5400) $PN 15
J 2
(-9310 5410);
DISPLAY 0.680851 (-9310 5410);
PAINT MONO (-9310 5410);
FORCEPROP 0 LASTPIN (-9300 6200) $PN 17
J 2
(-9310 6210);
DISPLAY 0.680851 (-9310 6210);
PAINT MONO (-9310 6210);
FORCEPROP 0 LASTPIN (-8100 5800) $PN 14
J 0
(-8090 5810);
DISPLAY 0.680851 (-8090 5810);
PAINT MONO (-8090 5810);
FORCEPROP 0 LASTPIN (-8100 5500) $PN 3
J 0
(-8090 5510);
DISPLAY 0.680851 (-8090 5510);
PAINT MONO (-8090 5510);
FORCEPROP 0 LASTPIN (-8100 5400) $PN 4
J 0
(-8090 5410);
DISPLAY 0.680851 (-8090 5410);
PAINT MONO (-8090 5410);
FORCEPROP 0 LASTPIN (-8100 5300) $PN 5
J 0
(-8090 5310);
DISPLAY 0.680851 (-8090 5310);
PAINT MONO (-8090 5310);
FORCEPROP 0 LASTPIN (-8100 5200) $PN 8
J 0
(-8090 5210);
DISPLAY 0.680851 (-8090 5210);
PAINT MONO (-8090 5210);
FORCEPROP 0 LASTPIN (-8100 5100) $PN 9
J 0
(-8090 5110);
DISPLAY 0.680851 (-8090 5110);
PAINT MONO (-8090 5110);
FORCEPROP 0 LASTPIN (-8100 5000) $PN 10
J 0
(-8090 5010);
DISPLAY 0.680851 (-8090 5010);
PAINT MONO (-8090 5010);
FORCEPROP 0 LASTPIN (-9300 6000) $PN 18
J 2
(-9310 6010);
DISPLAY 0.680851 (-9310 6010);
PAINT MONO (-9310 6010);
FORCEPROP 0 LASTPIN (-9300 5600) $PN 13
J 2
(-9310 5610);
DISPLAY 0.680851 (-9310 5610);
PAINT MONO (-9310 5610);
FORCEPROP 0 LASTPIN (-9300 5800) $PN 16
J 2
(-9310 5810);
DISPLAY 0.680851 (-9310 5810);
PAINT MONO (-9310 5810);
FORCEPROP 0 LASTPIN (-8100 6300) $PN 6
J 0
(-8090 6310);
DISPLAY 0.680851 (-8090 6310);
PAINT MONO (-8090 6310);
FORCEPROP 0 LASTPIN (-8100 6200) $PN 7
J 0
(-8090 6210);
DISPLAY 0.680851 (-8090 6210);
PAINT MONO (-8090 6210);
FORCEPROP 0 LASTPIN (-9300 6500) $PN 2
J 2
(-9310 6510);
DISPLAY 0.680851 (-9310 6510);
PAINT MONO (-9310 6510);
FORCEPROP 0 LASTPIN (-9300 6400) $PN 11
J 2
(-9310 6410);
DISPLAY 0.680851 (-9310 6410);
PAINT MONO (-9310 6410);
FORCEPROP 1 LAST VALUE TPS54424RNVT
J 0
(-9150 6900);
DISPLAY 1.212766 (-9150 6900);
PAINT GREEN (-9150 6900);
FORCEPROP 1 LAST CLS_PN G220-10657-01
J 0
(-9150 6800);
DISPLAY 1.212766 (-9150 6800);
PAINT GREEN (-9150 6800);
FORCEPROP 1 LAST PATH I42
J 0
(-9150 6650);
DISPLAY 1.212766 (-9150 6650);
PAINT GREEN (-9150 6650);
DISPLAY INVISIBLE (-9150 6650);
FORCEPROP 1 LAST CDS_LMAN_SYM_OUTLINE 0,0,1000,-1750
J 0
(-9200 6600);
DISPLAY 0.468085 (-9200 6600);
PAINT GREEN (-9200 6600);
DISPLAY INVISIBLE (-9200 6600);
FORCEPROP 2 LAST CDS_LIB stdlogic
J 0
(-9200 6600);
DISPLAY INVISIBLE (-9200 6600);
FORCEADD RESISTOR..1
(-11350 4100);
FORCEPROP 1 LAST $LOCATION R263
J 2
(-11451 4155);
DISPLAY 1.212766 (-11451 4155);
PAINT GREEN (-11451 4155);
FORCEPROP 0 LAST CDS_LOCATION R263
J 0
(-11200 4250);
DISPLAY 1.021277 (-11200 4250);
DISPLAY INVISIBLE (-11200 4250);
FORCEPROP 0 LAST $SEC 1
J 0
(-11200 4250);
DISPLAY 0.680851 (-11200 4250);
PAINT MONO (-11200 4250);
DISPLAY INVISIBLE (-11200 4250);
FORCEPROP 0 LAST CDS_SEC 1
J 0
(-11200 4250);
DISPLAY 1.021277 (-11200 4250);
DISPLAY INVISIBLE (-11200 4250);
FORCEPROP 0 LASTPIN (-11450 4100) $PN 1
J 2
(-11460 4110);
DISPLAY 0.680851 (-11460 4110);
PAINT MONO (-11460 4110);
FORCEPROP 0 LASTPIN (-11200 4100) $PN 2
J 0
(-11190 4110);
DISPLAY 0.680851 (-11190 4110);
PAINT MONO (-11190 4110);
FORCEPROP 1 LAST VALUE 0OHM
J 0
(-11200 4150);
DISPLAY 1.212766 (-11200 4150);
PAINT GREEN (-11200 4150);
FORCEPROP 0 LAST PACKAGE 0402
J 0
(-11400 4000);
DISPLAY 1.021277 (-11400 4000);
FORCEPROP 1 LAST PATH I47
J 0
(-11547 4205);
DISPLAY 1.212766 (-11547 4205);
PAINT GREEN (-11547 4205);
DISPLAY INVISIBLE (-11547 4205);
FORCEPROP 1 LAST TOLERANCE -
J 0
(-11547 4355);
DISPLAY 1.212766 (-11547 4355);
PAINT GREEN (-11547 4355);
DISPLAY INVISIBLE (-11547 4355);
FORCEPROP 2 LAST CDS_LIB passive
J 0
(-11350 4100);
DISPLAY INVISIBLE (-11350 4100);
FORCEPROP 1 LAST CDS_LMAN_SYM_OUTLINE -50,50,100,-50
J 0
(-11350 4100);
DISPLAY 0.468085 (-11350 4100);
PAINT GREEN (-11350 4100);
DISPLAY INVISIBLE (-11350 4100);
FORCEPROP 1 LAST CLS_PN G155-100R0-J0
J 0
(-11486 4300);
DISPLAY 1.212766 (-11486 4300);
PAINT GREEN (-11486 4300);
DISPLAY INVISIBLE (-11486 4300);
FORCEADD OFFPAGE_OUT..1
(-10000 4100);
FORCEPROP 2 LAST $XR1 29E1< 
J 0
(-9735 4100);
DISPLAY 0.638298 (-9735 4100);
PAINT MONO (-9735 4100);
FORCEPROP 2 LAST $XR0 25F6<> 
J 0
(-9945 4100);
DISPLAY 0.638298 (-9945 4100);
PAINT MONO (-9945 4100);
FORCEPROP 2 LAST PATH I48
J 0
(-9950 4200);
DISPLAY 1.021277 (-9950 4200);
DISPLAY INVISIBLE (-9950 4200);
FORCEPROP 1 LAST OFFPAGE TRUE
J 0
(-9990 4155);
DISPLAY 0.808511 (-9990 4155);
PAINT GREEN (-9990 4155);
DISPLAY INVISIBLE (-9990 4155);
FORCEPROP 1 LAST BODY_TYPE COMMENT
J 0
(-9990 4235);
DISPLAY 0.808511 (-9990 4235);
PAINT GREEN (-9990 4235);
DISPLAY INVISIBLE (-9990 4235);
FORCEPROP 2 LAST CDS_LIB cls
J 0
(-10000 4100);
DISPLAY INVISIBLE (-10000 4100);
FORCEPROP 1 LAST CDS_LMAN_SYM_OUTLINE -50,50,50,-50
J 0
(-10000 4100);
DISPLAY 0.468085 (-10000 4100);
PAINT GREEN (-10000 4100);
DISPLAY INVISIBLE (-10000 4100);
FORCEADD VCC..1
(-13050 4750);
FORCEPROP 3 LASTPIN (-13000 4700) SIG_NAME XP3R3V\g
J 0
(-12990 4710);
DISPLAY 0.659574 (-12990 4710);
PAINT MONO (-12990 4710);
DISPLAY INVISIBLE (-12990 4710);
FORCEPROP 1 LAST HDL_POWER XP3R3V
J 1
(-12995 4805);
DISPLAY 1.021277 (-12995 4805);
PAINT GREEN (-12995 4805);
FORCEPROP 0 LAST VOLTAGE 3.3
J 0
(-13200 4900);
DISPLAY 1.021277 (-13200 4900);
DISPLAY BOTH (-13200 4900);
FORCEPROP 1 LAST PATH I49
J 0
(-13015 4840);
DISPLAY 0.808511 (-13015 4840);
PAINT GREEN (-13015 4840);
DISPLAY INVISIBLE (-13015 4840);
FORCEPROP 1 LAST BODY_TYPE PLUMBING
J 0
(-13095 4707);
DISPLAY 0.340426 (-13095 4707);
PAINT GREEN (-13095 4707);
DISPLAY INVISIBLE (-13095 4707);
FORCEPROP 2 LAST CDS_LIB cls
J 0
(-13050 4750);
DISPLAY INVISIBLE (-13050 4750);
FORCEPROP 1 LAST CDS_LMAN_SYM_OUTLINE -250,250,250,-250
J 0
(-13050 4750);
DISPLAY 0.468085 (-13050 4750);
PAINT GREEN (-13050 4750);
DISPLAY INVISIBLE (-13050 4750);
FORCEADD GND_SG..1
(-13800 6800);
FORCEPROP 3 LASTPIN (-13750 6850) SIG_NAME SG\g
J 0
(-13740 6860);
DISPLAY 0.659574 (-13740 6860);
PAINT MONO (-13740 6860);
DISPLAY INVISIBLE (-13740 6860);
FORCEPROP 1 LAST HDL_POWER SG
J 1
(-13745 6705);
DISPLAY 0.808511 (-13745 6705);
PAINT GREEN (-13745 6705);
FORCEPROP 1 LAST PATH I5
J 0
(-13765 6800);
DISPLAY 0.808511 (-13765 6800);
PAINT GREEN (-13765 6800);
DISPLAY INVISIBLE (-13765 6800);
FORCEPROP 1 LAST BODY_TYPE PLUMBING
J 0
(-13785 6785);
DISPLAY 0.808511 (-13785 6785);
PAINT GREEN (-13785 6785);
DISPLAY INVISIBLE (-13785 6785);
FORCEPROP 2 LAST CDS_LIB cls
J 0
(-13800 6800);
DISPLAY INVISIBLE (-13800 6800);
FORCEPROP 1 LAST CDS_LMAN_SYM_OUTLINE 0,0,100,-50
J 0
(-13800 6800);
DISPLAY 0.468085 (-13800 6800);
PAINT GREEN (-13800 6800);
DISPLAY INVISIBLE (-13800 6800);
FORCEADD CAPACITOR..2
(-12850 5800);
FORCEPROP 1 LAST $LOCATION C286
J 0
(-12800 5650);
DISPLAY 1.212766 (-12800 5650);
PAINT GREEN (-12800 5650);
FORCEPROP 0 LAST CDS_LOCATION C286
J 0
(-12750 5950);
DISPLAY 1.021277 (-12750 5950);
DISPLAY INVISIBLE (-12750 5950);
FORCEPROP 0 LAST $SEC 1
J 0
(-12750 5950);
DISPLAY 0.680851 (-12750 5950);
PAINT MONO (-12750 5950);
DISPLAY INVISIBLE (-12750 5950);
FORCEPROP 0 LAST CDS_SEC 1
J 0
(-12750 5950);
DISPLAY 1.021277 (-12750 5950);
DISPLAY INVISIBLE (-12750 5950);
FORCEPROP 0 LASTPIN (-12850 5900) $PN 1
R 1
J 0
(-12860 5910);
DISPLAY 0.680851 (-12860 5910);
PAINT MONO (-12860 5910);
FORCEPROP 0 LASTPIN (-12850 5650) $PN 2
R 1
J 2
(-12860 5640);
DISPLAY 0.680851 (-12860 5640);
PAINT MONO (-12860 5640);
FORCEPROP 0 LAST VOLTAGE 25V
J 0
(-12750 6100);
DISPLAY 1.021277 (-12750 6100);
FORCEPROP 1 LAST VALUE 0.22UF
J 0
(-12750 5850);
DISPLAY 1.212766 (-12750 5850);
PAINT GREEN (-12750 5850);
FORCEPROP 0 LAST PACKAGE 0402
J 0
(-12750 6000);
DISPLAY 1.021277 (-12750 6000);
FORCEPROP 1 LAST PATH I51
J 0
(-12950 5850);
DISPLAY 1.212766 (-12950 5850);
PAINT GREEN (-12950 5850);
DISPLAY INVISIBLE (-12950 5850);
FORCEPROP 1 LAST CLS_PN G105-0B224-DK
J 0
(-12950 5850);
DISPLAY 1.212766 (-12950 5850);
PAINT GREEN (-12950 5850);
DISPLAY INVISIBLE (-12950 5850);
FORCEPROP 1 LAST TOLERANCE 10%
J 0
(-13000 5900);
DISPLAY 1.212766 (-13000 5900);
PAINT GREEN (-13000 5900);
DISPLAY INVISIBLE (-13000 5900);
FORCEPROP 2 LAST CDS_LIB passive
J 0
(-12850 5800);
DISPLAY INVISIBLE (-12850 5800);
FORCEPROP 1 LAST CDS_LMAN_SYM_OUTLINE -50,0,50,-50
J 0
(-12850 5800);
DISPLAY 0.468085 (-12850 5800);
PAINT GREEN (-12850 5800);
DISPLAY INVISIBLE (-12850 5800);
FORCEADD OFFPAGE_IN..1
(-13500 6200);
FORCEPROP 1 LAST BODY_TYPE COMMENT
J 0
(-13490 6335);
DISPLAY 0.808511 (-13490 6335);
PAINT GREEN (-13490 6335);
DISPLAY INVISIBLE (-13490 6335);
FORCEPROP 1 LAST OFFPAGE TRUE
J 0
(-13490 6255);
DISPLAY 0.808511 (-13490 6255);
PAINT GREEN (-13490 6255);
DISPLAY INVISIBLE (-13490 6255);
FORCEPROP 1 LAST CDS_LMAN_SYM_OUTLINE -50,50,50,-50
J 0
(-13500 6200);
DISPLAY 0.468085 (-13500 6200);
PAINT GREEN (-13500 6200);
DISPLAY INVISIBLE (-13500 6200);
FORCEPROP 2 LAST PATH I52
J 0
(-13450 6300);
DISPLAY 1.021277 (-13450 6300);
DISPLAY INVISIBLE (-13450 6300);
FORCEPROP 2 LAST CDS_LIB cls
J 0
(-13500 6200);
DISPLAY INVISIBLE (-13500 6200);
FORCEPROP 2 LAST $XR0 25F6<> 
J 0
(-13714 6200);
DISPLAY 0.638298 (-13714 6200);
PAINT MONO (-13714 6200);
FORCEADD CAPACITOR..2
(-13750 7200);
FORCEPROP 1 LAST $LOCATION C76
J 0
(-13650 7050);
DISPLAY 1.212766 (-13650 7050);
PAINT GREEN (-13650 7050);
FORCEPROP 0 LAST CDS_LOCATION C76
J 0
(-13650 7450);
DISPLAY 1.021277 (-13650 7450);
DISPLAY INVISIBLE (-13650 7450);
FORCEPROP 0 LAST $SEC 1
J 0
(-13650 7450);
DISPLAY 0.680851 (-13650 7450);
PAINT MONO (-13650 7450);
DISPLAY INVISIBLE (-13650 7450);
FORCEPROP 0 LAST CDS_SEC 1
J 0
(-13650 7450);
DISPLAY 1.021277 (-13650 7450);
DISPLAY INVISIBLE (-13650 7450);
FORCEPROP 0 LASTPIN (-13750 7300) $PN 1
R 1
J 0
(-13760 7310);
DISPLAY 0.680851 (-13760 7310);
PAINT MONO (-13760 7310);
FORCEPROP 0 LASTPIN (-13750 7050) $PN 2
R 1
J 2
(-13760 7040);
DISPLAY 0.680851 (-13760 7040);
PAINT MONO (-13760 7040);
FORCEPROP 1 LAST VALUE 0.1UF
J 0
(-13650 7200);
DISPLAY 1.212766 (-13650 7200);
PAINT GREEN (-13650 7200);
FORCEPROP 0 LAST PACKAGE 0402
J 0
(-13650 7300);
DISPLAY 1.021277 (-13650 7300);
FORCEPROP 0 LAST VOLTAGE 25V
J 0
(-13650 7400);
DISPLAY 1.021277 (-13650 7400);
FORCEPROP 1 LAST PATH I6
J 0
(-13850 7250);
DISPLAY 1.212766 (-13850 7250);
PAINT GREEN (-13850 7250);
DISPLAY INVISIBLE (-13850 7250);
FORCEPROP 1 LAST TOLERANCE 10%
J 0
(-13900 7300);
DISPLAY 1.212766 (-13900 7300);
PAINT GREEN (-13900 7300);
DISPLAY INVISIBLE (-13900 7300);
FORCEPROP 1 LAST CLS_PN G105-0B104-EK
J 0
(-13850 7250);
DISPLAY 1.212766 (-13850 7250);
PAINT GREEN (-13850 7250);
DISPLAY INVISIBLE (-13850 7250);
FORCEPROP 2 LAST CDS_LIB passive
J 0
(-13750 7200);
DISPLAY INVISIBLE (-13750 7200);
FORCEPROP 1 LAST CDS_LMAN_SYM_OUTLINE -50,0,50,-50
J 0
(-13750 7200);
DISPLAY 0.468085 (-13750 7200);
PAINT GREEN (-13750 7200);
DISPLAY INVISIBLE (-13750 7200);
FORCEADD FERRITEBEAD..1
(-13250 7500);
FORCEPROP 1 LAST $LOCATION L8
J 2
(-13310 7559);
DISPLAY 1.212766 (-13310 7559);
PAINT GREEN (-13310 7559);
FORCEPROP 0 LAST CDS_LOCATION L8
J 0
(-13300 7650);
DISPLAY 1.021277 (-13300 7650);
DISPLAY INVISIBLE (-13300 7650);
FORCEPROP 0 LAST $SEC 1
J 0
(-13300 7650);
DISPLAY 0.680851 (-13300 7650);
PAINT MONO (-13300 7650);
DISPLAY INVISIBLE (-13300 7650);
FORCEPROP 0 LAST CDS_SEC 1
J 0
(-13300 7650);
DISPLAY 1.021277 (-13300 7650);
DISPLAY INVISIBLE (-13300 7650);
FORCEPROP 0 LASTPIN (-13350 7450) $PN 1
J 2
(-13360 7460);
DISPLAY 0.680851 (-13360 7460);
PAINT MONO (-13360 7460);
FORCEPROP 0 LASTPIN (-12950 7450) $PN 2
J 0
(-12940 7460);
DISPLAY 0.680851 (-12940 7460);
PAINT MONO (-12940 7460);
FORCEPROP 0 LAST PACKAGE 0603
J 0
(-13200 7550);
DISPLAY 1.021277 (-13200 7550);
FORCEPROP 1 LAST VALUE 26OHM
J 0
(-12900 7450);
DISPLAY 1.212766 (-12900 7450);
PAINT GREEN (-12900 7450);
FORCEPROP 1 LAST TOLERANCE 25%
J 0
(-13350 7550);
DISPLAY 1.212766 (-13350 7550);
PAINT GREEN (-13350 7550);
DISPLAY INVISIBLE (-13350 7550);
FORCEPROP 1 LAST PATH I7
J 2
(-13300 7550);
DISPLAY 1.212766 (-13300 7550);
PAINT GREEN (-13300 7550);
DISPLAY INVISIBLE (-13300 7550);
FORCEPROP 1 LAST CLS_PN G191-10101-01
J 2
(-13300 7550);
DISPLAY 1.212766 (-13300 7550);
PAINT GREEN (-13300 7550);
DISPLAY INVISIBLE (-13300 7550);
FORCEPROP 2 LAST CDS_LIB passive
J 0
(-13250 7500);
DISPLAY INVISIBLE (-13250 7500);
FORCEPROP 1 LAST CDS_LMAN_SYM_OUTLINE 0,0,200,-100
J 0
(-13250 7500);
DISPLAY 0.468085 (-13250 7500);
PAINT GREEN (-13250 7500);
DISPLAY INVISIBLE (-13250 7500);
FORCEADD GND_SG..1
(-12400 5250);
FORCEPROP 3 LASTPIN (-12350 5300) SIG_NAME SG\g
J 0
(-12340 5310);
DISPLAY 0.659574 (-12340 5310);
PAINT MONO (-12340 5310);
DISPLAY INVISIBLE (-12340 5310);
FORCEPROP 1 LAST HDL_POWER SG
J 1
(-12345 5155);
DISPLAY 0.808511 (-12345 5155);
PAINT GREEN (-12345 5155);
FORCEPROP 1 LAST PATH I8
J 0
(-12365 5250);
DISPLAY 0.808511 (-12365 5250);
PAINT GREEN (-12365 5250);
DISPLAY INVISIBLE (-12365 5250);
FORCEPROP 1 LAST BODY_TYPE PLUMBING
J 0
(-12385 5235);
DISPLAY 0.808511 (-12385 5235);
PAINT GREEN (-12385 5235);
DISPLAY INVISIBLE (-12385 5235);
FORCEPROP 2 LAST CDS_LIB cls
J 0
(-12400 5250);
DISPLAY INVISIBLE (-12400 5250);
FORCEPROP 1 LAST CDS_LMAN_SYM_OUTLINE 0,0,100,-50
J 0
(-12400 5250);
DISPLAY 0.468085 (-12400 5250);
PAINT GREEN (-12400 5250);
DISPLAY INVISIBLE (-12400 5250);
FORCEADD CAPACITOR..2
(-11600 5300);
FORCEPROP 1 LAST $LOCATION C49
J 0
(-11500 5150);
DISPLAY 1.212766 (-11500 5150);
PAINT GREEN (-11500 5150);
FORCEPROP 0 LAST CDS_LOCATION C49
J 0
(-11550 5150);
DISPLAY 1.212766 (-11550 5150);
PAINT GREEN (-11550 5150);
DISPLAY INVISIBLE (-11550 5150);
FORCEPROP 0 LAST $SEC 1
J 0
(-11550 5450);
DISPLAY 0.680851 (-11550 5450);
PAINT MONO (-11550 5450);
DISPLAY INVISIBLE (-11550 5450);
FORCEPROP 0 LAST CDS_SEC 1
J 0
(-11550 5450);
DISPLAY 1.021277 (-11550 5450);
DISPLAY INVISIBLE (-11550 5450);
FORCEPROP 0 LASTPIN (-11600 5400) $PN 1
R 1
J 0
(-11610 5410);
DISPLAY 0.680851 (-11610 5410);
PAINT MONO (-11610 5410);
FORCEPROP 0 LASTPIN (-11600 5150) $PN 2
R 1
J 2
(-11610 5140);
DISPLAY 0.680851 (-11610 5140);
PAINT MONO (-11610 5140);
FORCEPROP 0 LAST PACKAGE 0402
J 0
(-11500 5250);
DISPLAY 1.021277 (-11500 5250);
FORCEPROP 1 LAST VALUE 0.022UF
J 0
(-11550 5350);
DISPLAY 1.212766 (-11550 5350);
PAINT GREEN (-11550 5350);
FORCEPROP 1 LAST PATH I9
J 0
(-11700 5350);
DISPLAY 1.212766 (-11700 5350);
PAINT GREEN (-11700 5350);
DISPLAY INVISIBLE (-11700 5350);
FORCEPROP 1 LAST TOLERANCE 10%
J 0
(-11750 5400);
DISPLAY 1.212766 (-11750 5400);
PAINT GREEN (-11750 5400);
DISPLAY INVISIBLE (-11750 5400);
FORCEPROP 2 LAST CDS_LIB passive
J 0
(-11600 5300);
DISPLAY INVISIBLE (-11600 5300);
FORCEPROP 1 LAST CDS_LMAN_SYM_OUTLINE -50,0,50,-50
J 0
(-11600 5300);
DISPLAY 0.468085 (-11600 5300);
PAINT GREEN (-11600 5300);
DISPLAY INVISIBLE (-11600 5300);
FORCEPROP 1 LAST CLS_PN G105-0B223-EK
J 0
(-11700 5350);
DISPLAY 1.212766 (-11700 5350);
PAINT GREEN (-11700 5350);
DISPLAY INVISIBLE (-11700 5350);
FORCEADD SHEET_A1..1
(150 -450);
FORCEPROP 2 LAST CUSTOM_TXT_CDS <XR_PAGE_TITLE>
J 0
(-15420 10900);
DISPLAY 0.638298 (-15420 10900);
PAINT PINK (-15420 10900);
FORCEPROP 1 LAST CUSTOM_TXT_CDS <DOCNO>
J 0
(-1900 -65);
DISPLAY 0.978723 (-1900 -65);
FORCEPROP 1 LAST CUSTOM_TXT_CDS <CON_PAGE_NUM>
J 0
(-2005 -400);
DISPLAY 0.978723 (-2005 -400);
FORCEPROP 1 LAST CUSTOM_TXT_CDS <DATE>
J 0
(-550 -275);
DISPLAY 0.978723 (-550 -275);
FORCEPROP 1 LAST CUSTOM_TXT_CDS <TITLE>
J 1
(-1635 180);
DISPLAY 0.978723 (-1635 180);
FORCEPROP 1 LAST CUSTOM_TXT_CDS <DESIGNER>
J 0
(-550 150);
DISPLAY 0.978723 (-550 150);
FORCEPROP 1 LAST CUSTOM_TXT_CDS <CON_TOTAL_PAGES>
J 0
(-1695 -400);
DISPLAY 0.808511 (-1695 -400);
FORCEPROP 1 LAST CUSTOM_TXT_CDS <ASSY_PN>
J 0
(-1900 -275);
DISPLAY 0.978723 (-1900 -275);
FORCEPROP 1 LAST CUSTOM_TXT_CDS <DOCREV>
J 0
(-550 -75);
DISPLAY 0.978723 (-550 -75);
FORCEPROP 1 LAST TITLE XP3R3V
J 0
(-2350 400);
DISPLAY 3.042553 (-2350 400);
PAINT GREEN (-2350 400);
FORCEPROP 1 LAST COMMENT_BODY TRUE
J 0
(160 -395);
DISPLAY 0.808511 (160 -395);
PAINT GREEN (160 -395);
DISPLAY INVISIBLE (160 -395);
FORCEPROP 2 LAST CDS_LIB cls
J 0
(150 -450);
DISPLAY INVISIBLE (150 -450);
FORCEPROP 1 LAST CDS_LMAN_SYM_OUTLINE -15850,11500,200,-200
J 0
(150 -450);
DISPLAY 0.468085 (150 -450);
PAINT GREEN (150 -450);
DISPLAY INVISIBLE (150 -450);
FORCEPROP 2 LAST PAGE_BORDER TRUE
J 0
(-15420 10900);
DISPLAY 0.638298 (-15420 10900);
PAINT PINK (-15420 10900);
DISPLAY INVISIBLE (-15420 10900);
FORCEPROP 2 LAST CDS_XR_PAGE_TITLE CR-28 : @TIMECARD_LIB.TIMECARD(SCH_1):PAGE28
J 0
(-15420 10900);
DISPLAY 0.638298 (-15420 10900);
PAINT PINK (-15420 10900);
DISPLAY INVISIBLE (-15420 10900);
WIRE 16 -1 (-13750 7050)(-13750 6850);
WIRE 16 -1 (-13000 4550)(-13000 4700);
WIRE 16 -1 (-3500 6650)(-3150 6650);
WIRE 16 -1 (-3150 6650)(-3150 6550);
WIRE 16 -1 (-11950 3600)(-11950 3450);
WIRE 16 -1 (-12350 5300)(-12350 5450);
WIRE 16 -1 (-12350 5450)(-12350 5650);
WIRE 16 -1 (-12850 5450)(-12350 5450);
WIRE 16 -1 (-12850 5650)(-12850 5450);
WIRE 16 -1 (-13300 5450)(-12850 5450);
WIRE 16 -1 (-13300 5600)(-13300 5450);
WIRE 16 -1 (-1050 6050)(-1050 6300);
WIRE 16 -1 (-1050 6650)(-1050 6300);
WIRE 16 -1 (-1500 6300)(-1050 6300);
WIRE 16 -1 (-2000 6300)(-1500 6300);
WIRE 16 -1 (-1500 6050)(-1500 6300);
WIRE 16 -1 (-2000 6050)(-2000 6300);
WIRE 16 -1 (-2500 6300)(-2000 6300);
WIRE 16 -1 (-2500 6300)(-3100 6300);
WIRE 16 -1 (-2500 6050)(-2500 6300);
WIRE 16 -1 (-3100 6000)(-3100 6300);
WIRE 16 -1 (-3100 6300)(-4400 6300);
WIRE 16 -1 (-1050 5600)(-1050 5800);
WIRE 16 -1 (-1050 5600)(-1050 5300);
WIRE 16 -1 (-1500 5600)(-1050 5600);
WIRE 16 -1 (-1500 5800)(-1500 5600);
WIRE 16 -1 (-2000 5600)(-1500 5600);
WIRE 16 -1 (-2000 5800)(-2000 5600);
WIRE 16 -1 (-2500 5600)(-2000 5600);
WIRE 16 -1 (-2500 5800)(-2500 5600);
WIRE 16 -1 (-7250 4250)(-7750 4250);
WIRE 16 -1 (-7750 5000)(-7750 4250);
WIRE 16 -1 (-7750 4000)(-7750 4250);
WIRE 16 -1 (-7750 5100)(-7750 5000);
WIRE 16 -1 (-8100 5000)(-7750 5000);
WIRE 16 -1 (-7750 5200)(-7750 5100);
WIRE 16 -1 (-8100 5100)(-7750 5100);
WIRE 16 -1 (-7750 5300)(-7750 5200);
WIRE 16 -1 (-8100 5200)(-7750 5200);
WIRE 16 -1 (-7750 5400)(-7750 5300);
WIRE 16 -1 (-8100 5300)(-7750 5300);
WIRE 16 -1 (-7750 5500)(-7750 5400);
WIRE 16 -1 (-8100 5400)(-7750 5400);
WIRE 16 -1 (-8100 5500)(-7750 5500);
WIRE 16 -1 (-13750 7850)(-13750 7450);
WIRE 16 -1 (-13750 7450)(-13350 7450);
WIRE 16 -1 (-13750 7300)(-13750 7450);
WIRE 16 -1 (-10550 6650)(-10550 6800);
WIRE 16 -1 (-10550 7000)(-10550 6800);
WIRE 16 -1 (-10550 6800)(-11100 6800);
WIRE 16 -1 (-11100 7000)(-11100 6800);
WIRE 16 -1 (-11100 6800)(-11550 6800);
WIRE 16 -1 (-11550 6800)(-11550 7000);
WIRE 16 -1 (-12000 6800)(-11550 6800);
WIRE 16 -1 (-12000 7000)(-12000 6800);
WIRE 16 -1 (-9300 6200)(-12350 6200);
FORCEPROP 2 LAST SIG_NAME XP3R3V_EN
J 0
(-11410 6210);
DISPLAY 1.021277 (-11410 6210);
WIRE 16 -1 (-12350 6200)(-12550 6200);
WIRE 16 -1 (-12350 5900)(-12350 6200);
WIRE 16 -1 (-12550 6700)(-12550 6200);
WIRE 16 -1 (-12850 6200)(-12550 6200);
WIRE 16 -1 (-12850 6200)(-13300 6200);
WIRE 16 -1 (-12850 5900)(-12850 6200);
WIRE 16 -1 (-13450 6200)(-13300 6200);
WIRE 16 -1 (-13300 5850)(-13300 6200);
WIRE 16 -1 (-13000 4300)(-13000 4100);
WIRE 16 -1 (-11950 4100)(-13000 4100);
FORCEPROP 2 LAST SIG_NAME R_XP3R3V_PG
J 0
(-12760 4110);
DISPLAY 1.021277 (-12760 4110);
WIRE 16 -1 (-11850 4100)(-11950 4100);
WIRE 16 -1 (-11950 3850)(-11950 4100);
WIRE 16 -1 (-11850 6000)(-11850 4100);
WIRE 16 -1 (-11450 4100)(-11850 4100);
WIRE 16 -1 (-11850 6000)(-9300 6000);
WIRE 16 -1 (-11600 5400)(-11600 5800);
WIRE 16 -1 (-11600 5800)(-9300 5800);
FORCEPROP 2 LAST SIG_NAME XP3R3V_SS
J 0
(-10310 5810);
DISPLAY 1.021277 (-10310 5810);
WIRE 16 -1 (-9500 5000)(-9300 5000);
WIRE 16 -1 (-9500 5000)(-9500 4650);
WIRE 16 -1 (-9500 4650)(-9800 4650);
WIRE 16 -1 (-9800 4900)(-9800 4650);
WIRE 16 -1 (-9800 4650)(-10400 4650);
WIRE 16 -1 (-10400 4750)(-10400 4650);
WIRE 16 -1 (-10400 4650)(-11050 4650);
FORCEPROP 2 LAST SIG_NAME XP3R3V_AGND
J 0
(-11060 4560);
DISPLAY 1.021277 (-11060 4560);
PAINT PEACH (-11060 4560);
FORCEPROP 0 LAST $PHYS_NET_NAME XP5R0V_AGND
J 0
(-11060 4608);
DISPLAY INVISIBLE (-11060 4608);
WIRE 16 -1 (-11050 5150)(-11050 4650);
WIRE 16 -1 (-11600 4650)(-11050 4650);
WIRE 16 -1 (-11600 5150)(-11600 4650);
WIRE 16 -1 (-11200 4100)(-10050 4100);
FORCEPROP 2 LAST SIG_NAME XP3R3V_PG
J 0
(-10610 4110);
DISPLAY 1.021277 (-10610 4110);
WIRE 16 -1 (-8100 5800)(-5150 5800);
FORCEPROP 2 LAST SIG_NAME XP3R3V_FB_R_TO_AGND
J 1
(-7410 5810);
DISPLAY 1.021277 (-7410 5810);
WIRE 16 -1 (-5150 5800)(-5150 4950);
WIRE 16 -1 (-5150 4950)(-4550 4950);
WIRE 16 -1 (-5150 4700)(-5150 4950);
WIRE 16 -1 (-4550 4950)(-3750 4950);
WIRE 16 -1 (-4550 4700)(-4550 4950);
WIRE 16 -1 (-3750 5150)(-3750 4950);
WIRE 16 -1 (-3100 4950)(-3750 4950);
WIRE 16 -1 (-3100 5200)(-3100 4950);
WIRE 16 -1 (-3100 5600)(-3750 5600);
WIRE 16 -1 (-3100 5750)(-3100 5600);
WIRE 16 -1 (-3100 5600)(-3100 5450);
WIRE 16 -1 (-3750 5600)(-3750 5400);
WIRE 16 -1 (-8100 6200)(-7950 6200);
WIRE 16 -1 (-7950 6200)(-7950 6300);
WIRE 16 -1 (-7950 6300)(-5450 6300);
FORCEPROP 2 LAST SIG_NAME XP3R3V_SW
J 1
(-7560 6310);
DISPLAY 1.021277 (-7560 6310);
WIRE 16 -1 (-8100 6300)(-7950 6300);
WIRE 16 -1 (-5450 6500)(-5450 6300);
WIRE 16 -1 (-5450 6300)(-5100 6300);
WIRE 16 -1 (-5100 6300)(-4750 6300);
WIRE 16 -1 (-5100 6300)(-5100 6650);
WIRE 16 -1 (-5800 6500)(-5450 6500);
WIRE 16 -1 (-4750 6650)(-5100 6650);
WIRE 16 -1 (-6800 4250)(-5150 4250);
FORCEPROP 2 LAST SIG_NAME XP3R3V_AGND
J 0
(-6710 4160);
DISPLAY 1.021277 (-6710 4160);
PAINT PEACH (-6710 4160);
WIRE 16 -1 (-4550 4250)(-5150 4250);
WIRE 16 -1 (-5150 4450)(-5150 4250);
WIRE 16 -1 (-4550 4450)(-4550 4250);
WIRE 16 -1 (-10050 6400)(-9300 6400);
WIRE 16 -1 (-10050 6500)(-10050 6400);
WIRE 16 -1 (-10050 7450)(-10050 6500);
WIRE 16 -1 (-9300 6500)(-10050 6500);
WIRE 16 -1 (-10050 7450)(-10550 7450);
WIRE 16 -1 (-10550 7250)(-10550 7450);
WIRE 16 -1 (-11100 7450)(-10550 7450);
FORCEPROP 2 LAST SIG_NAME VIN_XP3R3
J 0
(-9960 6510);
DISPLAY 1.021277 (-9960 6510);
WIRE 16 -1 (-11100 7250)(-11100 7450);
WIRE 16 -1 (-11100 7450)(-11550 7450);
WIRE 16 -1 (-11550 7250)(-11550 7450);
WIRE 16 -1 (-11550 7450)(-12000 7450);
WIRE 16 -1 (-12000 7250)(-12000 7450);
WIRE 16 -1 (-12000 7450)(-12550 7450);
WIRE 16 -1 (-12950 7450)(-12550 7450);
WIRE 16 -1 (-12550 6950)(-12550 7450);
WIRE 16 -1 (-9300 5600)(-11050 5600);
FORCEPROP 2 LAST SIG_NAME XP3R3V_RT
J 0
(-10310 5610);
DISPLAY 1.021277 (-10310 5610);
WIRE 16 -1 (-11050 5400)(-11050 5600);
WIRE 8 -1 (-1350 3300)(-2200 3300);
WIRE 8 -1 (-400 3300)(-1350 3300);
WIRE 8 -1 (-1350 3300)(-1350 3450);
WIRE 8 -1 (-2200 3300)(-2200 3450);
WIRE 8 -1 (-1350 3450)(-2200 3450);
WIRE 8 -1 (-2200 3450)(-2200 3600);
WIRE 8 -1 (-400 3450)(-1350 3450);
WIRE 8 -1 (-1350 3450)(-1350 3600);
WIRE 8 -1 (-400 3300)(-400 3450);
WIRE 8 -1 (-400 3450)(-400 3600);
WIRE 8 -1 (-1350 3600)(-2200 3600);
WIRE 8 -1 (-400 3600)(-1350 3600);
WIRE 8 -1 (-1350 3600)(-1350 3750);
WIRE 8 -1 (-2200 3600)(-2200 3750);
WIRE 8 -1 (-1350 3750)(-2200 3750);
WIRE 8 -1 (-2200 3750)(-2200 3900);
WIRE 8 -1 (-400 3750)(-1350 3750);
WIRE 8 -1 (-1350 3750)(-1350 3900);
WIRE 8 -1 (-400 3600)(-400 3750);
WIRE 8 -1 (-400 3750)(-400 3900);
WIRE 8 -1 (-2200 3900)(-1350 3900);
WIRE 8 -1 (-1350 3900)(-400 3900);
WIRE 8 -1 (-1350 3900)(-1350 4050);
WIRE 8 -1 (-2200 3900)(-2200 4050);
WIRE 8 -1 (-2200 4050)(-2200 4200);
WIRE 8 -1 (-2200 4050)(-1350 4050);
WIRE 8 -1 (-1350 4050)(-1350 4200);
WIRE 8 -1 (-1350 4050)(-400 4050);
WIRE 8 -1 (-400 3900)(-400 4050);
WIRE 8 -1 (-400 4050)(-400 4200);
WIRE 8 -1 (-2200 4200)(-1350 4200);
WIRE 8 -1 (-1350 4200)(-400 4200);
WIRE 8 -1 (-1350 4200)(-1350 4350);
WIRE 8 -1 (-2200 4200)(-2200 4350);
WIRE 8 -1 (-2200 4350)(-1350 4350);
WIRE 8 -1 (-2200 4500)(-2200 4350);
WIRE 8 -1 (-1350 4350)(-400 4350);
WIRE 8 -1 (-1350 4350)(-1350 4500);
WIRE 8 -1 (-400 4200)(-400 4350);
WIRE 8 -1 (-400 4500)(-400 4350);
WIRE 8 -1 (-2200 4500)(-1350 4500);
WIRE 8 -1 (-1350 4500)(-1350 4650);
WIRE 8 -1 (-1350 4500)(-400 4500);
WIRE 8 -1 (-2200 4650)(-2200 4500);
WIRE 8 -1 (-1350 4650)(-2200 4650);
WIRE 8 -1 (-400 4650)(-400 4500);
WIRE 8 -1 (-400 4650)(-1350 4650);
WIRE 16 -1 (-8100 6500)(-6950 6500);
FORCEPROP 2 LAST SIG_NAME XP3R3V_BT
J 1
(-7560 6510);
DISPLAY 1.021277 (-7560 6510);
WIRE 16 -1 (-10400 5050)(-10400 5000);
WIRE 16 -1 (-10400 5300)(-10400 5400);
WIRE 16 -1 (-10400 5400)(-9800 5400);
FORCEPROP 2 LAST SIG_NAME XP3R3V_COMP
J 0
(-10310 5410);
DISPLAY 1.021277 (-10310 5410);
WIRE 16 -1 (-9800 5400)(-9300 5400);
WIRE 16 -1 (-9800 5150)(-9800 5400);
WIRE 16 -1 (-6700 6500)(-6050 6500);
WIRE 16 -1 (-3750 6650)(-4500 6650);
DOT 1 (-12550 6200);
DOT 1 (-12550 7450);
DOT 1 (-12850 5450);
DOT 1 (-12850 6200);
DOT 1 (-12350 5450);
DOT 1 (-2000 6300);
DOT 1 (-1500 6300);
DOT 1 (-400 4500);
DOT 1 (-400 4200);
DOT 1 (-400 4350);
DOT 1 (-1050 5600);
DOT 1 (-1500 5600);
DOT 1 (-1350 4650);
DOT 1 (-1350 4500);
DOT 1 (-1350 4350);
DOT 1 (-1350 4200);
DOT 1 (-2500 6300);
DOT 1 (-3100 6300);
DOT 1 (-2200 4500);
DOT 1 (-2200 4350);
DOT 1 (-2200 4200);
DOT 1 (-3100 5600);
DOT 1 (-400 4050);
DOT 1 (-400 3900);
DOT 1 (-400 3750);
DOT 1 (-400 3600);
DOT 1 (-400 3450);
DOT 1 (-1350 3900);
DOT 1 (-1350 4050);
DOT 1 (-1350 3750);
DOT 1 (-1350 3600);
DOT 1 (-1350 3300);
DOT 1 (-1350 3450);
DOT 1 (-2200 4050);
DOT 1 (-2200 3900);
DOT 1 (-2200 3750);
DOT 1 (-2200 3600);
DOT 1 (-2200 3450);
DOT 1 (-5100 6300);
DOT 1 (-5450 6300);
DOT 1 (-3750 4950);
DOT 1 (-4550 4950);
DOT 1 (-5150 4950);
DOT 1 (-5150 4250);
DOT 1 (-7950 6300);
DOT 1 (-7750 5400);
DOT 1 (-7750 5200);
DOT 1 (-7750 5300);
DOT 1 (-7750 5000);
DOT 1 (-7750 5100);
DOT 1 (-7750 4250);
DOT 1 (-10550 7450);
DOT 1 (-10050 6500);
DOT 1 (-10550 6800);
DOT 1 (-11100 7450);
DOT 1 (-11100 6800);
DOT 1 (-11550 6800);
DOT 1 (-9800 5400);
DOT 1 (-9800 4650);
DOT 1 (-11050 4650);
DOT 1 (-12000 7450);
DOT 1 (-12350 6200);
DOT 1 (-1050 6300);
DOT 1 (-2000 5600);
DOT 1 (-11850 4100);
DOT 1 (-11950 4100);
DOT 1 (-10400 4650);
DOT 1 (-13750 7450);
DOT 1 (-11550 7450);
CIRCLE (-10800 7200)(-10260 7200);
PAINT PEACH (-10800 7200);
DOT 1 (-13300 6200);
FORCENOTE
XP3R3V
(-8500 9400) 0;
DISPLAY LEFT (-8500 9400);
DISPLAY 6.148936 (-8500 9400);
PAINT VIOLET (-8500 9400);
FORCENOTE
2.5MS
(-1050 4100) 0;
DISPLAY LEFT (-1050 4100);
DISPLAY 1.595745 (-1050 4100);
FORCENOTE
12V
(-1000 4400) 0;
DISPLAY LEFT (-1000 4400);
DISPLAY 1.595745 (-1000 4400);
FORCENOTE
XP3R3V
(-1100 4550) 0;
DISPLAY LEFT (-1100 4550);
DISPLAY 1.595745 (-1100 4550);
FORCENOTE
XP3R3V
(-1100 4250) 0;
DISPLAY LEFT (-1100 4250);
DISPLAY 1.595745 (-1100 4250);
FORCENOTE
SS
(-1850 4100) 0;
DISPLAY LEFT (-1850 4100);
DISPLAY 1.595745 (-1850 4100);
FORCENOTE
VOUT
(-1950 4250) 0;
DISPLAY LEFT (-1950 4250);
DISPLAY 1.595745 (-1950 4250);
FORCENOTE
108%*VOUT
(-1200 3500) 0;
DISPLAY LEFT (-1200 3500);
DISPLAY 1.595745 (-1200 3500);
FORCENOTE
1.35A
(-1000 3800) 0;
DISPLAY LEFT (-1000 3800);
DISPLAY 1.595745 (-1000 3800);
FORCENOTE
10A
(-1000 3650) 0;
DISPLAY LEFT (-1000 3650);
DISPLAY 1.595745 (-1000 3650);
FORCENOTE
 +/- 1%
(-1150 3350) 0;
DISPLAY LEFT (-1150 3350);
DISPLAY 1.595745 (-1150 3350);
FORCENOTE
500KHZ
(-1100 3950) 0;
DISPLAY LEFT (-1100 3950);
DISPLAY 1.595745 (-1100 3950);
FORCENOTE
 RIPPLE
(-2100 3350) 0;
DISPLAY LEFT (-2100 3350);
DISPLAY 1.595745 (-2100 3350);
FORCENOTE
IMAX
(-1950 3800) 0;
DISPLAY LEFT (-1950 3800);
DISPLAY 1.595745 (-1950 3800);
FORCENOTE
OCP
(-1900 3650) 0;
DISPLAY LEFT (-1900 3650);
DISPLAY 1.595745 (-1900 3650);
FORCENOTE
OVP
(-1900 3500) 0;
DISPLAY LEFT (-1900 3500);
DISPLAY 1.595745 (-1900 3500);
FORCENOTE
FSW
(-1900 3950) 0;
DISPLAY LEFT (-1900 3950);
DISPLAY 1.595745 (-1900 3950);
FORCENOTE
VFB=0.6V
(-3700 4850) 0;
DISPLAY LEFT (-3700 4850);
DISPLAY 1.021277 (-3700 4850);
FORCENOTE
1.35A
(-1500 6350) 0;
DISPLAY LEFT (-1500 6350);
DISPLAY 1.595745 (-1500 6350);
FORCENOTE
POWER RAIL
(-2150 4550) 0;
DISPLAY LEFT (-2150 4550);
DISPLAY 1.595745 (-2150 4550);
FORCENOTE
XP3R3V
(-2150 4700) 0;
DISPLAY LEFT (-2150 4700);
DISPLAY 1.595745 (-2150 4700);
PAINT VIOLET (-2150 4700);
FORCENOTE
PLACE NEAR TWO VIN SEPARATELY
(-11450 6650) 0;
DISPLAY LEFT (-11450 6650);
DISPLAY 1.021277 (-11450 6650);
PAINT PINK (-11450 6650);
FORCENOTE
VIN
(-1900 4400) 0;
DISPLAY LEFT (-1900 4400);
DISPLAY 1.595745 (-1900 4400);
QUIT
